FILE_TYPE = MACRO_DRAWING;
SET COLOR_WIRE YELLOW;
SET COLOR_PROP MONO;
SET COLOR_DOT WHITE;
SET COLOR_ARC YELLOW;
SET COLOR_BODY GREEN;
SET COLOR_NOTE MONO;
SET PROP_DISPLAY VALUE;
SET PAGE_NUMBER P170;
FORCEADD TTL08..1
(-1400 4375);
FORCEPROP 2 LASTPIN (-1550 4425) $PN 1
J 2
(-1560 4435);
DISPLAY 0.617021 (-1560 4435);
PAINT ORANGE (-1560 4435);
FORCEPROP 2 LASTPIN (-1550 4325) $PN 2
J 2
(-1560 4335);
DISPLAY 0.617021 (-1560 4335);
PAINT ORANGE (-1560 4335);
FORCEPROP 1 LAST MATERIAL IC
J 0
(-1500 4550);
DISPLAY 0.617021 (-1500 4550);
PAINT SKYBLUE (-1500 4550);
FORCEPROP 1 LAST PART_NUMBER D90404-001
J 0
(-1500 4225);
DISPLAY 0.617021 (-1500 4225);
PAINT BLUE (-1500 4225);
FORCEPROP 1 LAST VALUE 74LVC08A
J 0
(-1500 4500);
DISPLAY 0.617021 (-1500 4500);
PAINT SKYBLUE (-1500 4500);
FORCEPROP 2 LASTPIN (-1250 4375) $PN 3
J 0
(-1240 4385);
DISPLAY 0.617021 (-1240 4385);
PAINT ORANGE (-1240 4385);
FORCEPROP 1 LAST LOCATION U8E1
J 0
(-1500 4600);
DISPLAY 0.617021 (-1500 4600);
PAINT AQUA (-1500 4600);
FORCEPROP 1 LAST POWER_GROUP VCC=P3V3_STBY;GND=GND;TH=GND
J 0
(-1500 4175);
DISPLAY 0.617021 (-1500 4175);
PAINT ORANGE (-1500 4175);
FORCEPROP 2 LAST CDS_LIB mstr_ttl
J 0
(-1400 4375);
PAINT MONO (-1400 4375);
DISPLAY INVISIBLE (-1400 4375);
FORCEPROP 1 LAST PATH I10
J 0
(-1025 4550);
DISPLAY 0.978723 (-1025 4550);
PAINT BLUE (-1025 4550);
DISPLAY INVISIBLE (-1025 4550);
FORCEPROP 2 LAST CDS_LOCATION U8E1
J 0
(-1500 4600);
DISPLAY 0.617021 (-1500 4600);
PAINT AQUA (-1500 4600);
DISPLAY INVISIBLE (-1500 4600);
FORCEPROP 1 LAST PACK_TYPE QFN15
J 0
(-1500 4650);
DISPLAY 0.978723 (-1500 4650);
PAINT SKYBLUE (-1500 4650);
DISPLAY INVISIBLE (-1500 4650);
FORCEPROP 2 LAST ROOM FAST_PROCHOT
J 0
(-1500 4650);
DISPLAY 1.021277 (-1500 4650);
PAINT ORANGE (-1500 4650);
DISPLAY INVISIBLE (-1500 4650);
FORCEPROP 2 LAST SEC 4
J 0
(-1500 4650);
DISPLAY 0.680851 (-1500 4650);
PAINT MONO (-1500 4650);
DISPLAY INVISIBLE (-1500 4650);
FORCEPROP 2 LAST BOM_COST FAST_PROCHOT
J 0
(-1500 4700);
DISPLAY 1.021277 (-1500 4700);
PAINT ORANGE (-1500 4700);
DISPLAY INVISIBLE (-1500 4700);
FORCEPROP 2 LAST SEC_TYPE QFN15
J 0
(-1500 4650);
DISPLAY 1.021277 (-1500 4650);
PAINT ORANGE (-1500 4650);
DISPLAY INVISIBLE (-1500 4650);
FORCEADD TTL08..1
(-1400 3650);
FORCEPROP 2 LASTPIN (-1550 3700) $PN 4
J 2
(-1560 3710);
DISPLAY 0.617021 (-1560 3710);
PAINT ORANGE (-1560 3710);
FORCEPROP 2 LASTPIN (-1550 3600) $PN 5
J 2
(-1560 3610);
DISPLAY 0.617021 (-1560 3610);
PAINT ORANGE (-1560 3610);
FORCEPROP 1 LAST PART_NUMBER D90404-001
J 0
(-1500 3500);
DISPLAY 0.617021 (-1500 3500);
PAINT BLUE (-1500 3500);
FORCEPROP 1 LAST MATERIAL IC
J 0
(-1500 3825);
DISPLAY 0.617021 (-1500 3825);
PAINT SKYBLUE (-1500 3825);
FORCEPROP 1 LAST LOCATION U8E1
J 0
(-1500 3875);
DISPLAY 0.617021 (-1500 3875);
PAINT AQUA (-1500 3875);
FORCEPROP 1 LAST VALUE 74LVC08A
J 0
(-1500 3775);
DISPLAY 0.617021 (-1500 3775);
PAINT SKYBLUE (-1500 3775);
FORCEPROP 2 LASTPIN (-1250 3650) $PN 6
J 0
(-1240 3660);
DISPLAY 0.617021 (-1240 3660);
PAINT ORANGE (-1240 3660);
FORCEPROP 1 LAST POWER_GROUP VCC=P3V3_STBY;GND=GND;TH=GND
J 0
(-1500 3450);
DISPLAY 0.617021 (-1500 3450);
PAINT ORANGE (-1500 3450);
FORCEPROP 2 LAST CDS_LIB mstr_ttl
J 0
(-1400 3650);
PAINT MONO (-1400 3650);
DISPLAY INVISIBLE (-1400 3650);
FORCEPROP 1 LAST PACK_TYPE QFN15
J 0
(-1500 3925);
DISPLAY 0.978723 (-1500 3925);
PAINT SKYBLUE (-1500 3925);
DISPLAY INVISIBLE (-1500 3925);
FORCEPROP 2 LAST ROOM FAST_PROCHOT
J 0
(-1500 3925);
DISPLAY 1.021277 (-1500 3925);
PAINT ORANGE (-1500 3925);
DISPLAY INVISIBLE (-1500 3925);
FORCEPROP 2 LAST CDS_LOCATION U8E1
J 0
(-1500 3875);
DISPLAY 0.617021 (-1500 3875);
PAINT AQUA (-1500 3875);
DISPLAY INVISIBLE (-1500 3875);
FORCEPROP 2 LAST SEC 3
J 0
(-1500 3925);
DISPLAY 0.680851 (-1500 3925);
PAINT MONO (-1500 3925);
DISPLAY INVISIBLE (-1500 3925);
FORCEPROP 2 LAST BOM_COST FAST_PROCHOT
J 0
(-1500 3975);
DISPLAY 1.021277 (-1500 3975);
PAINT ORANGE (-1500 3975);
DISPLAY INVISIBLE (-1500 3975);
FORCEPROP 2 LAST SEC_TYPE QFN15
J 0
(-1500 3925);
DISPLAY 1.021277 (-1500 3925);
PAINT ORANGE (-1500 3925);
DISPLAY INVISIBLE (-1500 3925);
FORCEPROP 1 LAST PATH I11
J 0
(-1025 3825);
DISPLAY 0.978723 (-1025 3825);
PAINT BLUE (-1025 3825);
DISPLAY INVISIBLE (-1025 3825);
FORCEADD TTL08..1
(-250 4075);
FORCEPROP 2 LASTPIN (-400 4025) $PN 13
J 2
(-410 4035);
DISPLAY 0.617021 (-410 4035);
PAINT ORANGE (-410 4035);
FORCEPROP 1 LAST PART_NUMBER D90404-001
J 0
(-350 3925);
DISPLAY 0.617021 (-350 3925);
PAINT BLUE (-350 3925);
FORCEPROP 2 LASTPIN (-100 4075) $PN 11
J 0
(-90 4085);
DISPLAY 0.617021 (-90 4085);
PAINT ORANGE (-90 4085);
FORCEPROP 1 LAST MATERIAL IC
J 0
(-350 4250);
DISPLAY 0.617021 (-350 4250);
PAINT SKYBLUE (-350 4250);
FORCEPROP 2 LASTPIN (-400 4125) $PN 12
J 2
(-410 4135);
DISPLAY 0.617021 (-410 4135);
PAINT ORANGE (-410 4135);
FORCEPROP 1 LAST LOCATION U8E1
J 0
(-350 4300);
DISPLAY 0.617021 (-350 4300);
PAINT AQUA (-350 4300);
FORCEPROP 1 LAST VALUE 74LVC08A
J 0
(-350 4200);
DISPLAY 0.617021 (-350 4200);
PAINT SKYBLUE (-350 4200);
FORCEPROP 1 LAST POWER_GROUP VCC=P3V3_STBY;GND=GND;TH=GND
J 0
(-350 3875);
DISPLAY 0.617021 (-350 3875);
PAINT ORANGE (-350 3875);
FORCEPROP 2 LAST CDS_LIB mstr_ttl
J 0
(-250 4075);
PAINT MONO (-250 4075);
DISPLAY INVISIBLE (-250 4075);
FORCEPROP 2 LAST CDS_LOCATION U8E1
J 0
(-350 4300);
DISPLAY 0.617021 (-350 4300);
PAINT AQUA (-350 4300);
DISPLAY INVISIBLE (-350 4300);
FORCEPROP 2 LAST ROOM FAST_PROCHOT
J 0
(-350 4350);
DISPLAY 1.021277 (-350 4350);
PAINT ORANGE (-350 4350);
DISPLAY INVISIBLE (-350 4350);
FORCEPROP 1 LAST PACK_TYPE QFN15
J 0
(-350 4350);
DISPLAY 0.978723 (-350 4350);
PAINT SKYBLUE (-350 4350);
DISPLAY INVISIBLE (-350 4350);
FORCEPROP 2 LAST SEC_TYPE QFN15
J 0
(-350 4350);
DISPLAY 1.021277 (-350 4350);
PAINT ORANGE (-350 4350);
DISPLAY INVISIBLE (-350 4350);
FORCEPROP 2 LAST SEC 1
J 0
(-350 4350);
DISPLAY 0.680851 (-350 4350);
PAINT MONO (-350 4350);
DISPLAY INVISIBLE (-350 4350);
FORCEPROP 2 LAST BOM_COST FAST_PROCHOT
J 0
(-350 4400);
DISPLAY 1.021277 (-350 4400);
PAINT ORANGE (-350 4400);
DISPLAY INVISIBLE (-350 4400);
FORCEPROP 1 LAST PATH I12
J 0
(125 4250);
DISPLAY 0.978723 (125 4250);
PAINT BLUE (125 4250);
DISPLAY INVISIBLE (125 4250);
FORCEADD OFFPAGE..1
(-2525 4325);
FORCEPROP 2 LAST $XR0 200 
J 0
(-2777 4325);
DISPLAY 0.638298 (-2777 4325);
PAINT MONO (-2777 4325);
FORCEPROP 1 LAST COMMENT_BODY TRUE
J 0
(-2400 4225);
DISPLAY 0.872340 (-2400 4225);
PAINT GREEN (-2400 4225);
DISPLAY INVISIBLE (-2400 4225);
FORCEPROP 2 LAST CDS_LIB mstr_standard
J 0
(-2525 4325);
PAINT MONO (-2525 4325);
DISPLAY INVISIBLE (-2525 4325);
FORCEPROP 2 LAST PATH I15
J 0
(-2475 4400);
DISPLAY 1.021277 (-2475 4400);
PAINT ORANGE (-2475 4400);
DISPLAY INVISIBLE (-2475 4400);
FORCEPROP 1 LAST OFFPAGE TRUE
J 0
(-2200 4200);
DISPLAY 0.872340 (-2200 4200);
PAINT GREEN (-2200 4200);
DISPLAY INVISIBLE (-2200 4200);
FORCEADD OFFPAGE..1
(-2475 3700);
FORCEPROP 2 LAST $XR0 200 
J 0
(-2727 3700);
DISPLAY 0.638298 (-2727 3700);
PAINT MONO (-2727 3700);
FORCEPROP 2 LAST $XR1 120 
J 0
(-2847 3700);
DISPLAY 0.638298 (-2847 3700);
PAINT MONO (-2847 3700);
FORCEPROP 2 LAST $XR2 145 
J 0
(-2967 3700);
DISPLAY 0.638298 (-2967 3700);
PAINT MONO (-2967 3700);
FORCEPROP 1 LAST OFFPAGE TRUE
J 0
(-2150 3575);
DISPLAY 0.872340 (-2150 3575);
PAINT GREEN (-2150 3575);
DISPLAY INVISIBLE (-2150 3575);
FORCEPROP 2 LAST CDS_LIB mstr_standard
J 0
(-2475 3700);
PAINT MONO (-2475 3700);
DISPLAY INVISIBLE (-2475 3700);
FORCEPROP 1 LAST COMMENT_BODY TRUE
J 0
(-2350 3600);
DISPLAY 0.872340 (-2350 3600);
PAINT GREEN (-2350 3600);
DISPLAY INVISIBLE (-2350 3600);
FORCEPROP 2 LAST PATH I16
J 0
(-2425 3775);
DISPLAY 1.021277 (-2425 3775);
PAINT ORANGE (-2425 3775);
DISPLAY INVISIBLE (-2425 3775);
FORCEADD OFFPAGE..1
(-2475 3600);
FORCEPROP 2 LAST $XR0 200 
J 0
(-2727 3600);
DISPLAY 0.638298 (-2727 3600);
PAINT MONO (-2727 3600);
FORCEPROP 2 LAST $XR1 120 
J 0
(-2847 3600);
DISPLAY 0.638298 (-2847 3600);
PAINT MONO (-2847 3600);
FORCEPROP 2 LAST $XR2 145 
J 0
(-2967 3600);
DISPLAY 0.638298 (-2967 3600);
PAINT MONO (-2967 3600);
FORCEPROP 1 LAST OFFPAGE TRUE
J 0
(-2150 3475);
DISPLAY 0.872340 (-2150 3475);
PAINT GREEN (-2150 3475);
DISPLAY INVISIBLE (-2150 3475);
FORCEPROP 1 LAST COMMENT_BODY TRUE
J 0
(-2350 3500);
DISPLAY 0.872340 (-2350 3500);
PAINT GREEN (-2350 3500);
DISPLAY INVISIBLE (-2350 3500);
FORCEPROP 2 LAST CDS_LIB mstr_standard
J 0
(-2475 3600);
PAINT MONO (-2475 3600);
DISPLAY INVISIBLE (-2475 3600);
FORCEPROP 2 LAST PATH I17
J 0
(-2425 3675);
DISPLAY 1.021277 (-2425 3675);
PAINT ORANGE (-2425 3675);
DISPLAY INVISIBLE (-2425 3675);
FORCEADD OFFPAGE..2
(800 4075);
FORCEPROP 2 LAST $XR0 191 
J 0
(989 4075);
DISPLAY 0.638298 (989 4075);
PAINT MONO (989 4075);
FORCEPROP 1 LAST COMMENT_BODY TRUE
J 0
(755 3980);
DISPLAY 0.872340 (755 3980);
PAINT GREEN (755 3980);
DISPLAY INVISIBLE (755 3980);
FORCEPROP 1 LAST OFFPAGE TRUE
J 0
(1125 3950);
DISPLAY 0.872340 (1125 3950);
PAINT GREEN (1125 3950);
DISPLAY INVISIBLE (1125 3950);
FORCEPROP 2 LAST CDS_LIB mstr_standard
J 0
(800 4075);
PAINT MONO (800 4075);
DISPLAY INVISIBLE (800 4075);
FORCEPROP 2 LAST PATH I18
J 0
(850 4150);
DISPLAY 1.021277 (850 4150);
PAINT ORANGE (850 4150);
DISPLAY INVISIBLE (850 4150);
FORCEADD OFFPAGE..1
(-3750 2525);
FORCEPROP 2 LAST $XR0 191 
J 0
(-4032 2525);
DISPLAY 0.638298 (-4032 2525);
PAINT MONO (-4032 2525);
FORCEPROP 1 LAST COMMENT_BODY TRUE
J 0
(-3625 2425);
DISPLAY 0.872340 (-3625 2425);
PAINT GREEN (-3625 2425);
DISPLAY INVISIBLE (-3625 2425);
FORCEPROP 2 LAST CDS_LIB mstr_standard
J 0
(-3750 2525);
PAINT MONO (-3750 2525);
DISPLAY INVISIBLE (-3750 2525);
FORCEPROP 2 LAST PATH I19
J 0
(-3700 2600);
DISPLAY 1.021277 (-3700 2600);
PAINT ORANGE (-3700 2600);
DISPLAY INVISIBLE (-3700 2600);
FORCEPROP 1 LAST OFFPAGE TRUE
J 0
(-3425 2400);
DISPLAY 0.872340 (-3425 2400);
PAINT GREEN (-3425 2400);
DISPLAY INVISIBLE (-3425 2400);
FORCEADD RES..2
(-2350 5250);
FORCEPROP 1 LAST PACK_TYPE 0402
J 0
(-2310 5075);
DISPLAY 0.617021 (-2310 5075);
PAINT SKYBLUE (-2310 5075);
FORCEPROP 1 LASTPIN (-2350 5150) $PN 2
J 0
(-2345 5160);
DISPLAY 0.617021 (-2345 5160);
PAINT ORANGE (-2345 5160);
FORCEPROP 1 LASTPIN (-2350 5350) $PN 1
J 0
(-2345 5312);
DISPLAY 0.617021 (-2345 5312);
PAINT ORANGE (-2345 5312);
FORCEPROP 1 LAST LOCATION R2P3
J 0
(-2305 5375);
DISPLAY 0.617021 (-2305 5375);
PAINT AQUA (-2305 5375);
FORCEPROP 1 LAST VALUE 4.75K
J 0
(-2305 5325);
DISPLAY 0.617021 (-2305 5325);
PAINT SKYBLUE (-2305 5325);
FORCEPROP 1 LAST TOLERANCE 1%
J 0
(-2305 5275);
DISPLAY 0.617021 (-2305 5275);
PAINT SKYBLUE (-2305 5275);
FORCEPROP 1 LAST MATERIAL CHIP
J 0
(-2310 5175);
DISPLAY 0.617021 (-2310 5175);
PAINT SKYBLUE (-2310 5175);
FORCEPROP 1 LAST WATTAGE 1/16W
J 0
(-2310 5225);
DISPLAY 0.617021 (-2310 5225);
PAINT SKYBLUE (-2310 5225);
FORCEPROP 1 LAST PART_NUMBER G21796-072
J 0
(-2310 5125);
DISPLAY 0.617021 (-2310 5125);
PAINT BLUE (-2310 5125);
FORCEPROP 2 LAST CDS_LIB mstr_discrete
J 0
(-2350 5250);
PAINT MONO (-2350 5250);
DISPLAY INVISIBLE (-2350 5250);
FORCEPROP 2 LAST CDS_LOCATION R2P3
J 0
(-2305 5375);
DISPLAY 0.617021 (-2305 5375);
PAINT AQUA (-2305 5375);
DISPLAY INVISIBLE (-2305 5375);
FORCEPROP 2 LAST ROOM FAST_PROCHOT
J 0
(-2300 5425);
DISPLAY 1.021277 (-2300 5425);
PAINT ORANGE (-2300 5425);
DISPLAY INVISIBLE (-2300 5425);
FORCEPROP 1 LAST PATH I2
J 0
(-2300 5425);
DISPLAY 0.978723 (-2300 5425);
PAINT WHITE (-2300 5425);
DISPLAY INVISIBLE (-2300 5425);
FORCEPROP 2 LAST SEC 1
J 0
(-2300 5475);
PAINT MONO (-2300 5475);
DISPLAY INVISIBLE (-2300 5475);
FORCEPROP 2 LAST BOM_COST FAST_PROCHOT
J 0
(-2300 5475);
DISPLAY 1.021277 (-2300 5475);
PAINT ORANGE (-2300 5475);
DISPLAY INVISIBLE (-2300 5475);
FORCEPROP 2 LAST SEC_TYPE 0402
J 0
(-2300 5475);
DISPLAY 1.021277 (-2300 5475);
PAINT ORANGE (-2300 5475);
DISPLAY INVISIBLE (-2300 5475);
FORCEADD TTL1G126_A..1
(-2525 2525);
FORCEPROP 1 LASTPIN (-2675 2525) $PN 2
J 2
(-2650 2535);
DISPLAY 0.617021 (-2650 2535);
PAINT WHITE (-2650 2535);
FORCEPROP 1 LAST LOCATION U1R2
J 0
(-2575 2725);
DISPLAY 0.617021 (-2575 2725);
PAINT AQUA (-2575 2725);
FORCEPROP 1 LAST VALUE 74HC1G126
J 0
(-2575 2625);
DISPLAY 0.617021 (-2575 2625);
PAINT SKYBLUE (-2575 2625);
FORCEPROP 1 LAST MATERIAL IC
J 0
(-2575 2675);
DISPLAY 0.617021 (-2575 2675);
PAINT SKYBLUE (-2575 2675);
FORCEPROP 1 LAST PART_NUMBER A79322-001
J 0
(-2425 2435);
DISPLAY 0.617021 (-2425 2435);
PAINT BLUE (-2425 2435);
FORCEPROP 1 LASTPIN (-2525 2425) $PN 1
J 0
(-2520 2375);
DISPLAY 0.617021 (-2520 2375);
PAINT WHITE (-2520 2375);
FORCEPROP 1 LASTPIN (-2375 2525) $PN 4
J 0
(-2410 2535);
DISPLAY 0.617021 (-2410 2535);
PAINT WHITE (-2410 2535);
FORCEPROP 1 LAST POWER_GROUP VCC=P3V3_STBY;GND=GND;
J 0
(-2425 2385);
DISPLAY 0.617021 (-2425 2385);
PAINT ORANGE (-2425 2385);
FORCEPROP 1 LAST PACK_TYPE SOT
J 0
(-2575 2775);
DISPLAY 0.978723 (-2575 2775);
PAINT SKYBLUE (-2575 2775);
DISPLAY INVISIBLE (-2575 2775);
FORCEPROP 2 LAST ROOM FAST_PROCHOT
J 0
(-2575 2775);
DISPLAY 1.021277 (-2575 2775);
PAINT ORANGE (-2575 2775);
DISPLAY INVISIBLE (-2575 2775);
FORCEPROP 1 LAST PATH I20
J 2
(-2630 2625);
DISPLAY 0.978723 (-2630 2625);
PAINT GREEN (-2630 2625);
DISPLAY INVISIBLE (-2630 2625);
FORCEPROP 2 LAST CDS_LOCATION U1R2
J 0
(-2575 2725);
DISPLAY 0.617021 (-2575 2725);
PAINT AQUA (-2575 2725);
DISPLAY INVISIBLE (-2575 2725);
FORCEPROP 2 LAST SEC 1
J 0
(-2575 2775);
DISPLAY 0.680851 (-2575 2775);
PAINT MONO (-2575 2775);
DISPLAY INVISIBLE (-2575 2775);
FORCEPROP 2 LAST BOM_COST FAST_PROCHOT
J 0
(-2575 2825);
DISPLAY 1.021277 (-2575 2825);
PAINT ORANGE (-2575 2825);
DISPLAY INVISIBLE (-2575 2825);
FORCEPROP 2 LAST SEC_TYPE SOT
J 0
(-2575 2775);
DISPLAY 1.021277 (-2575 2775);
PAINT ORANGE (-2575 2775);
DISPLAY INVISIBLE (-2575 2775);
FORCEPROP 2 LAST CDS_LIB mstr_ttl
J 0
(-2525 2525);
PAINT MONO (-2525 2525);
DISPLAY INVISIBLE (-2525 2525);
FORCEADD P3V3_STBY..1
(-2350 5475);
FORCEPROP 3 LASTPIN (-2350 5425) SIG_NAME P3V3_STBY\g
J 0
(-2340 5435);
DISPLAY 0.659574 (-2340 5435);
PAINT MONO (-2340 5435);
DISPLAY INVISIBLE (-2340 5435);
FORCEPROP 1 LAST HDL_POWER P3V3_STBY
J 0
(-2650 5350);
DISPLAY 0.872340 (-2650 5350);
PAINT ORANGE (-2650 5350);
DISPLAY INVISIBLE (-2650 5350);
FORCEPROP 1 LAST PATH I3
J 0
(-2305 5477);
DISPLAY 0.340426 (-2305 5477);
PAINT GREEN (-2305 5477);
DISPLAY INVISIBLE (-2305 5477);
FORCEPROP 1 LAST BODY_TYPE PLUMBING
J 0
(-2395 5432);
DISPLAY 0.340426 (-2395 5432);
PAINT GREEN (-2395 5432);
DISPLAY INVISIBLE (-2395 5432);
FORCEPROP 2 LAST CDS_LIB mstr_symbols
J 0
(-2350 5475);
PAINT ORANGE (-2350 5475);
DISPLAY INVISIBLE (-2350 5475);
FORCEPROP 1 LAST SIZE 1B
J 0
(-2305 5497);
DISPLAY 0.340426 (-2305 5497);
PAINT GREEN (-2305 5497);
DISPLAY INVISIBLE (-2305 5497);
FORCEPROP 1 LAST VOLTAGE 3.3V
J 0
(-2395 5432);
DISPLAY 0.340426 (-2395 5432);
PAINT SKYBLUE (-2395 5432);
DISPLAY INVISIBLE (-2395 5432);
FORCEADD CAP_A..1
(-5150 1325);
FORCEPROP 1 LASTPIN (-5150 1225) $PN 2
J 0
(-5140 1205);
DISPLAY 0.617021 (-5140 1205);
PAINT ORANGE (-5140 1205);
FORCEPROP 1 LASTPIN (-5150 1425) $PN 1
J 0
(-5140 1405);
DISPLAY 0.617021 (-5140 1405);
PAINT ORANGE (-5140 1405);
FORCEPROP 1 LAST LOCATION C1R27
J 0
(-5100 1425);
DISPLAY 0.617021 (-5100 1425);
PAINT AQUA (-5100 1425);
FORCEPROP 1 LAST PART_NUMBER A36096-030
J 0
(-5100 1175);
DISPLAY 0.617021 (-5100 1175);
PAINT BLUE (-5100 1175);
FORCEPROP 1 LAST VALUE 0.1UF
J 0
(-5100 1375);
DISPLAY 0.617021 (-5100 1375);
PAINT SKYBLUE (-5100 1375);
FORCEPROP 1 LAST TOLERANCE 10%
J 0
(-5100 1275);
DISPLAY 0.617021 (-5100 1275);
PAINT SKYBLUE (-5100 1275);
FORCEPROP 1 LAST PACK_TYPE 0402V
J 0
(-5100 1125);
DISPLAY 0.617021 (-5100 1125);
PAINT SKYBLUE (-5100 1125);
FORCEPROP 1 LAST VOLTAGE 16V
J 0
(-5100 1325);
DISPLAY 0.617021 (-5100 1325);
PAINT SKYBLUE (-5100 1325);
FORCEPROP 1 LAST MATERIAL X7R
J 0
(-5100 1225);
DISPLAY 0.617021 (-5100 1225);
PAINT SKYBLUE (-5100 1225);
FORCEPROP 2 LAST CDS_LIB dev_discrete
J 0
(-5150 1325);
PAINT ORANGE (-5150 1325);
DISPLAY INVISIBLE (-5150 1325);
FORCEPROP 1 LAST PATH I30
J 0
(-5100 1475);
DISPLAY 0.978723 (-5100 1475);
PAINT WHITE (-5100 1475);
DISPLAY INVISIBLE (-5100 1475);
FORCEPROP 2 LAST CDS_SEC 1
J 0
(-5100 1475);
PAINT ORANGE (-5100 1475);
DISPLAY INVISIBLE (-5100 1475);
FORCEPROP 2 LAST ROOM FAST_PROCHOT
J 0
(-5100 1475);
DISPLAY 1.021277 (-5100 1475);
PAINT ORANGE (-5100 1475);
DISPLAY INVISIBLE (-5100 1475);
FORCEPROP 2 LAST CDS_LOCATION C1R27
J 0
(-5100 1425);
DISPLAY 0.617021 (-5100 1425);
PAINT AQUA (-5100 1425);
DISPLAY INVISIBLE (-5100 1425);
FORCEPROP 2 LAST SEC_TYPE 0402V
J 0
(-5100 1525);
DISPLAY 1.021277 (-5100 1525);
PAINT ORANGE (-5100 1525);
DISPLAY INVISIBLE (-5100 1525);
FORCEPROP 2 LAST SEC 1
J 0
(-5100 1525);
DISPLAY 0.680851 (-5100 1525);
PAINT MONO (-5100 1525);
DISPLAY INVISIBLE (-5100 1525);
FORCEPROP 2 LAST BOM_COST FAST_PROCHOT
J 0
(-5100 1525);
DISPLAY 1.021277 (-5100 1525);
PAINT ORANGE (-5100 1525);
DISPLAY INVISIBLE (-5100 1525);
FORCEADD GND..1
(-5150 1050);
FORCEPROP 3 LASTPIN (-5150 1100) SIG_NAME GND\g
J 0
(-5140 1110);
DISPLAY 0.659574 (-5140 1110);
PAINT MONO (-5140 1110);
DISPLAY INVISIBLE (-5140 1110);
FORCEPROP 1 LAST VOLTAGE 0.0V
J 0
(-5195 1007);
DISPLAY 0.340426 (-5195 1007);
PAINT SKYBLUE (-5195 1007);
DISPLAY INVISIBLE (-5195 1007);
FORCEPROP 1 LAST BODY_TYPE PLUMBING
J 0
(-5195 1007);
DISPLAY 0.340426 (-5195 1007);
PAINT GREEN (-5195 1007);
DISPLAY INVISIBLE (-5195 1007);
FORCEPROP 1 LAST HDL_POWER GND
J 0
(-5150 1200);
DISPLAY 0.872340 (-5150 1200);
PAINT GREEN (-5150 1200);
DISPLAY INVISIBLE (-5150 1200);
FORCEPROP 2 LAST CDS_LIB mstr_symbols
J 0
(-5150 1050);
PAINT ORANGE (-5150 1050);
DISPLAY INVISIBLE (-5150 1050);
FORCEPROP 1 LAST SIZE 1B
J 0
(-5075 1000);
DISPLAY 0.872340 (-5075 1000);
PAINT AQUA (-5075 1000);
DISPLAY INVISIBLE (-5075 1000);
FORCEPROP 1 LAST PATH I31
J 0
(-5075 1050);
DISPLAY 0.872340 (-5075 1050);
PAINT AQUA (-5075 1050);
DISPLAY INVISIBLE (-5075 1050);
FORCEADD P3V3_STBY..1
(-5150 1575);
FORCEPROP 3 LASTPIN (-5150 1525) SIG_NAME P3V3_STBY\g
J 0
(-5140 1535);
DISPLAY 0.659574 (-5140 1535);
PAINT MONO (-5140 1535);
DISPLAY INVISIBLE (-5140 1535);
FORCEPROP 1 LAST HDL_POWER P3V3_STBY
J 0
(-5450 1450);
DISPLAY 0.872340 (-5450 1450);
PAINT ORANGE (-5450 1450);
DISPLAY INVISIBLE (-5450 1450);
FORCEPROP 1 LAST VOLTAGE 3.3V
J 0
(-5195 1532);
DISPLAY 0.340426 (-5195 1532);
PAINT SKYBLUE (-5195 1532);
DISPLAY INVISIBLE (-5195 1532);
FORCEPROP 1 LAST BODY_TYPE PLUMBING
J 0
(-5195 1532);
DISPLAY 0.340426 (-5195 1532);
PAINT GREEN (-5195 1532);
DISPLAY INVISIBLE (-5195 1532);
FORCEPROP 2 LAST CDS_LIB mstr_symbols
J 0
(-5150 1575);
PAINT ORANGE (-5150 1575);
DISPLAY INVISIBLE (-5150 1575);
FORCEPROP 1 LAST SIZE 1B
J 0
(-5105 1597);
DISPLAY 0.340426 (-5105 1597);
PAINT GREEN (-5105 1597);
DISPLAY INVISIBLE (-5105 1597);
FORCEPROP 1 LAST PATH I32
J 0
(-5105 1577);
DISPLAY 0.340426 (-5105 1577);
PAINT GREEN (-5105 1577);
DISPLAY INVISIBLE (-5105 1577);
FORCEADD CAP_A..1
(-425 4775);
FORCEPROP 1 LAST PACK_TYPE 0402V
J 0
(-375 4575);
DISPLAY 0.617021 (-375 4575);
PAINT SKYBLUE (-375 4575);
FORCEPROP 1 LAST TOLERANCE 10%
J 0
(-375 4725);
DISPLAY 0.617021 (-375 4725);
PAINT SKYBLUE (-375 4725);
FORCEPROP 1 LAST VOLTAGE 16V
J 0
(-375 4775);
DISPLAY 0.617021 (-375 4775);
PAINT SKYBLUE (-375 4775);
FORCEPROP 1 LAST MATERIAL X7R
J 0
(-375 4675);
DISPLAY 0.617021 (-375 4675);
PAINT SKYBLUE (-375 4675);
FORCEPROP 1 LASTPIN (-425 4675) $PN 2
J 0
(-415 4655);
DISPLAY 0.617021 (-415 4655);
PAINT ORANGE (-415 4655);
FORCEPROP 1 LASTPIN (-425 4875) $PN 1
J 0
(-415 4855);
DISPLAY 0.617021 (-415 4855);
PAINT ORANGE (-415 4855);
FORCEPROP 1 LAST LOCATION C8D2
J 0
(-375 4875);
DISPLAY 0.617021 (-375 4875);
PAINT AQUA (-375 4875);
FORCEPROP 1 LAST PART_NUMBER A36096-030
J 0
(-375 4625);
DISPLAY 0.617021 (-375 4625);
PAINT BLUE (-375 4625);
FORCEPROP 1 LAST VALUE 0.1UF
J 0
(-375 4825);
DISPLAY 0.617021 (-375 4825);
PAINT SKYBLUE (-375 4825);
FORCEPROP 2 LAST CDS_LIB dev_discrete
J 0
(-425 4775);
PAINT ORANGE (-425 4775);
DISPLAY INVISIBLE (-425 4775);
FORCEPROP 2 LAST SEC 1
J 0
(-375 4975);
DISPLAY 0.680851 (-375 4975);
PAINT MONO (-375 4975);
DISPLAY INVISIBLE (-375 4975);
FORCEPROP 2 LAST BOM_COST FAST_PROCHOT
J 0
(-375 4975);
DISPLAY 1.021277 (-375 4975);
PAINT ORANGE (-375 4975);
DISPLAY INVISIBLE (-375 4975);
FORCEPROP 2 LAST SEC_TYPE 0402V
J 0
(-375 4975);
DISPLAY 1.021277 (-375 4975);
PAINT ORANGE (-375 4975);
DISPLAY INVISIBLE (-375 4975);
FORCEPROP 2 LAST CDS_SEC 1
J 0
(-375 4925);
PAINT ORANGE (-375 4925);
DISPLAY INVISIBLE (-375 4925);
FORCEPROP 2 LAST ROOM FAST_PROCHOT
J 0
(-375 4925);
DISPLAY 1.021277 (-375 4925);
PAINT ORANGE (-375 4925);
DISPLAY INVISIBLE (-375 4925);
FORCEPROP 1 LAST PATH I33
J 0
(-375 4925);
DISPLAY 0.978723 (-375 4925);
PAINT WHITE (-375 4925);
DISPLAY INVISIBLE (-375 4925);
FORCEPROP 2 LAST CDS_LOCATION C8D2
J 0
(-375 4875);
DISPLAY 0.617021 (-375 4875);
PAINT AQUA (-375 4875);
DISPLAY INVISIBLE (-375 4875);
FORCEADD GND..1
(-425 4500);
FORCEPROP 3 LASTPIN (-425 4550) SIG_NAME GND\g
J 0
(-415 4560);
DISPLAY 0.659574 (-415 4560);
PAINT MONO (-415 4560);
DISPLAY INVISIBLE (-415 4560);
FORCEPROP 1 LAST VOLTAGE 0.0V
J 0
(-470 4457);
DISPLAY 0.340426 (-470 4457);
PAINT SKYBLUE (-470 4457);
DISPLAY INVISIBLE (-470 4457);
FORCEPROP 2 LAST CDS_LIB mstr_symbols
J 0
(-425 4500);
PAINT ORANGE (-425 4500);
DISPLAY INVISIBLE (-425 4500);
FORCEPROP 1 LAST SIZE 1B
J 0
(-350 4450);
DISPLAY 0.872340 (-350 4450);
PAINT AQUA (-350 4450);
DISPLAY INVISIBLE (-350 4450);
FORCEPROP 1 LAST BODY_TYPE PLUMBING
J 0
(-470 4457);
DISPLAY 0.340426 (-470 4457);
PAINT GREEN (-470 4457);
DISPLAY INVISIBLE (-470 4457);
FORCEPROP 1 LAST PATH I34
J 0
(-350 4500);
DISPLAY 0.872340 (-350 4500);
PAINT AQUA (-350 4500);
DISPLAY INVISIBLE (-350 4500);
FORCEPROP 1 LAST HDL_POWER GND
J 0
(-425 4650);
DISPLAY 0.872340 (-425 4650);
PAINT GREEN (-425 4650);
DISPLAY INVISIBLE (-425 4650);
FORCEADD P3V3_STBY..1
(-425 5025);
FORCEPROP 3 LASTPIN (-425 4975) SIG_NAME P3V3_STBY\g
J 0
(-415 4985);
DISPLAY 0.659574 (-415 4985);
PAINT MONO (-415 4985);
DISPLAY INVISIBLE (-415 4985);
FORCEPROP 1 LAST HDL_POWER P3V3_STBY
J 0
(-725 4900);
DISPLAY 0.872340 (-725 4900);
PAINT ORANGE (-725 4900);
DISPLAY INVISIBLE (-725 4900);
FORCEPROP 2 LAST CDS_LIB mstr_symbols
J 0
(-425 5025);
PAINT ORANGE (-425 5025);
DISPLAY INVISIBLE (-425 5025);
FORCEPROP 1 LAST BODY_TYPE PLUMBING
J 0
(-470 4982);
DISPLAY 0.340426 (-470 4982);
PAINT GREEN (-470 4982);
DISPLAY INVISIBLE (-470 4982);
FORCEPROP 1 LAST VOLTAGE 3.3V
J 0
(-470 4982);
DISPLAY 0.340426 (-470 4982);
PAINT SKYBLUE (-470 4982);
DISPLAY INVISIBLE (-470 4982);
FORCEPROP 1 LAST SIZE 1B
J 0
(-380 5047);
DISPLAY 0.340426 (-380 5047);
PAINT GREEN (-380 5047);
DISPLAY INVISIBLE (-380 5047);
FORCEPROP 1 LAST PATH I35
J 0
(-380 5027);
DISPLAY 0.340426 (-380 5027);
PAINT GREEN (-380 5027);
DISPLAY INVISIBLE (-380 5027);
FORCEADD TTL1G126_A..1
(-3500 4775);
FORCEPROP 1 LASTPIN (-3650 4775) $PN 2
J 2
(-3625 4785);
DISPLAY 0.617021 (-3625 4785);
PAINT WHITE (-3625 4785);
FORCEPROP 1 LASTPIN (-3350 4775) $PN 4
J 0
(-3385 4785);
DISPLAY 0.617021 (-3385 4785);
PAINT WHITE (-3385 4785);
FORCEPROP 1 LASTPIN (-3500 4675) $PN 1
J 0
(-3495 4625);
DISPLAY 0.617021 (-3495 4625);
PAINT WHITE (-3495 4625);
FORCEPROP 1 LAST MATERIAL IC
J 0
(-3550 4925);
DISPLAY 0.617021 (-3550 4925);
PAINT SKYBLUE (-3550 4925);
FORCEPROP 1 LAST LOCATION U8D5
J 0
(-3550 4975);
DISPLAY 0.617021 (-3550 4975);
PAINT AQUA (-3550 4975);
FORCEPROP 1 LAST PART_NUMBER A79322-001
J 0
(-3400 4685);
DISPLAY 0.617021 (-3400 4685);
PAINT BLUE (-3400 4685);
FORCEPROP 1 LAST VALUE 74HC1G126
J 0
(-3550 4875);
DISPLAY 0.617021 (-3550 4875);
PAINT SKYBLUE (-3550 4875);
FORCEPROP 1 LAST POWER_GROUP VCC=P3V3_STBY;GND=GND;
J 0
(-3400 4635);
DISPLAY 0.617021 (-3400 4635);
PAINT ORANGE (-3400 4635);
FORCEPROP 1 LAST PATH I38
J 2
(-3605 4875);
DISPLAY 0.978723 (-3605 4875);
PAINT GREEN (-3605 4875);
DISPLAY INVISIBLE (-3605 4875);
FORCEPROP 2 LAST CDS_LIB mstr_ttl
J 0
(-3500 4775);
PAINT ORANGE (-3500 4775);
DISPLAY INVISIBLE (-3500 4775);
FORCEPROP 1 LAST PACK_TYPE SOT
J 0
(-3550 5025);
DISPLAY 0.978723 (-3550 5025);
PAINT SKYBLUE (-3550 5025);
DISPLAY INVISIBLE (-3550 5025);
FORCEPROP 2 LAST ROOM PROC_SIDEBAND
J 0
(-3550 5025);
DISPLAY 1.021277 (-3550 5025);
PAINT ORANGE (-3550 5025);
DISPLAY INVISIBLE (-3550 5025);
FORCEPROP 2 LAST BOM_COST PROC_SIDEBAND
J 0
(-3550 5075);
DISPLAY 1.021277 (-3550 5075);
PAINT ORANGE (-3550 5075);
DISPLAY INVISIBLE (-3550 5075);
FORCEPROP 2 LAST SEC_TYPE SOT
J 0
(-3550 5025);
DISPLAY 1.021277 (-3550 5025);
PAINT ORANGE (-3550 5025);
DISPLAY INVISIBLE (-3550 5025);
FORCEPROP 2 LAST SEC 1
J 0
(-3550 5025);
DISPLAY 0.680851 (-3550 5025);
PAINT MONO (-3550 5025);
DISPLAY INVISIBLE (-3550 5025);
FORCEPROP 2 LAST CDS_LOCATION U8D5
J 0
(-3550 4975);
DISPLAY 0.617021 (-3550 4975);
PAINT AQUA (-3550 4975);
DISPLAY INVISIBLE (-3550 4975);
FORCEADD P3V3_STBY..1
(-1575 5350);
FORCEPROP 3 LASTPIN (-1575 5300) SIG_NAME P3V3_STBY\g
J 0
(-1565 5310);
DISPLAY 0.659574 (-1565 5310);
PAINT MONO (-1565 5310);
DISPLAY INVISIBLE (-1565 5310);
FORCEPROP 1 LAST VOLTAGE 3.3V
J 0
(-1620 5307);
DISPLAY 0.340426 (-1620 5307);
PAINT SKYBLUE (-1620 5307);
DISPLAY INVISIBLE (-1620 5307);
FORCEPROP 1 LAST HDL_POWER P3V3_STBY
J 0
(-1875 5225);
DISPLAY 0.872340 (-1875 5225);
PAINT ORANGE (-1875 5225);
DISPLAY INVISIBLE (-1875 5225);
FORCEPROP 1 LAST BODY_TYPE PLUMBING
J 0
(-1620 5307);
DISPLAY 0.340426 (-1620 5307);
PAINT GREEN (-1620 5307);
DISPLAY INVISIBLE (-1620 5307);
FORCEPROP 2 LAST CDS_LIB mstr_symbols
J 0
(-1575 5350);
PAINT ORANGE (-1575 5350);
DISPLAY INVISIBLE (-1575 5350);
FORCEPROP 1 LAST PATH I39
J 0
(-1530 5352);
DISPLAY 0.340426 (-1530 5352);
PAINT GREEN (-1530 5352);
DISPLAY INVISIBLE (-1530 5352);
FORCEPROP 1 LAST SIZE 1B
J 0
(-1530 5372);
DISPLAY 0.340426 (-1530 5372);
PAINT GREEN (-1530 5372);
DISPLAY INVISIBLE (-1530 5372);
FORCEADD TTL1G07_A..1
(-2625 4775);
FORCEPROP 1 LAST MATERIAL IC
J 0
(-2675 4925);
DISPLAY 0.617021 (-2675 4925);
PAINT SKYBLUE (-2675 4925);
FORCEPROP 2 LASTPIN (-2725 4775) $PN 2
J 2
(-2735 4785);
DISPLAY 0.617021 (-2735 4785);
PAINT MONO (-2735 4785);
FORCEPROP 1 LAST POWER_GROUP VCC=P3V3_STBY;GND=GND
J 1
(-2675 4585);
DISPLAY 0.617021 (-2675 4585);
PAINT ORANGE (-2675 4585);
FORCEPROP 1 LAST LOCATION U8D3
J 0
(-2675 4975);
DISPLAY 0.617021 (-2675 4975);
PAINT AQUA (-2675 4975);
FORCEPROP 1 LAST PART_NUMBER C88419-001
J 0
(-2675 4640);
DISPLAY 0.617021 (-2675 4640);
PAINT BLUE (-2675 4640);
FORCEPROP 1 LAST VALUE 74LVC1G07
J 1
(-2625 4875);
DISPLAY 0.617021 (-2625 4875);
PAINT SKYBLUE (-2625 4875);
FORCEPROP 2 LASTPIN (-2475 4775) $PN 4
J 0
(-2465 4785);
DISPLAY 0.617021 (-2465 4785);
PAINT MONO (-2465 4785);
FORCEPROP 1 LAST PACK_TYPE SOP
J 0
(-2675 5025);
DISPLAY 0.978723 (-2675 5025);
PAINT SKYBLUE (-2675 5025);
DISPLAY INVISIBLE (-2675 5025);
FORCEPROP 2 LAST ROOM FAST_PROCHOT
J 0
(-2675 5025);
DISPLAY 1.021277 (-2675 5025);
PAINT ORANGE (-2675 5025);
DISPLAY INVISIBLE (-2675 5025);
FORCEPROP 1 LAST PATH I4
J 0
(-2575 4825);
DISPLAY 0.978723 (-2575 4825);
PAINT WHITE (-2575 4825);
DISPLAY INVISIBLE (-2575 4825);
FORCEPROP 2 LAST CDS_LOCATION U8D3
J 0
(-2675 4975);
DISPLAY 0.617021 (-2675 4975);
PAINT AQUA (-2675 4975);
DISPLAY INVISIBLE (-2675 4975);
FORCEPROP 2 LAST $SEC 1
J 0
(-2675 5025);
PAINT MONO (-2675 5025);
DISPLAY INVISIBLE (-2675 5025);
FORCEPROP 2 LAST CDS_SEC 1
J 0
(-2675 5025);
PAINT MONO (-2675 5025);
DISPLAY INVISIBLE (-2675 5025);
FORCEPROP 2 LAST CDS_LIB mstr_ttl
J 0
(-2625 4775);
PAINT MONO (-2625 4775);
DISPLAY INVISIBLE (-2625 4775);
FORCEPROP 2 LAST BOM_COST FAST_PROCHOT
J 0
(-2675 5075);
DISPLAY 1.021277 (-2675 5075);
PAINT ORANGE (-2675 5075);
DISPLAY INVISIBLE (-2675 5075);
FORCEADD CAP_A..1
(-1575 5100);
FORCEPROP 1 LASTPIN (-1575 5000) $PN 2
J 0
(-1565 4980);
DISPLAY 0.617021 (-1565 4980);
PAINT ORANGE (-1565 4980);
FORCEPROP 1 LAST PART_NUMBER A36096-030
J 0
(-1525 4950);
DISPLAY 0.617021 (-1525 4950);
PAINT BLUE (-1525 4950);
FORCEPROP 1 LAST TOLERANCE 10%
J 0
(-1525 5050);
DISPLAY 0.617021 (-1525 5050);
PAINT SKYBLUE (-1525 5050);
FORCEPROP 1 LAST PACK_TYPE 0402V
J 0
(-1525 4900);
DISPLAY 0.617021 (-1525 4900);
PAINT SKYBLUE (-1525 4900);
FORCEPROP 1 LAST MATERIAL X7R
J 0
(-1525 5000);
DISPLAY 0.617021 (-1525 5000);
PAINT SKYBLUE (-1525 5000);
FORCEPROP 1 LAST VOLTAGE 16V
J 0
(-1525 5100);
DISPLAY 0.617021 (-1525 5100);
PAINT SKYBLUE (-1525 5100);
FORCEPROP 1 LASTPIN (-1575 5200) $PN 1
J 0
(-1565 5180);
DISPLAY 0.617021 (-1565 5180);
PAINT ORANGE (-1565 5180);
FORCEPROP 1 LAST LOCATION C8E2
J 0
(-1525 5200);
DISPLAY 0.617021 (-1525 5200);
PAINT AQUA (-1525 5200);
FORCEPROP 1 LAST VALUE 0.1UF
J 0
(-1525 5150);
DISPLAY 0.617021 (-1525 5150);
PAINT SKYBLUE (-1525 5150);
FORCEPROP 2 LAST CDS_LIB dev_discrete
J 0
(-1575 5100);
PAINT ORANGE (-1575 5100);
DISPLAY INVISIBLE (-1575 5100);
FORCEPROP 2 LAST CDS_LOCATION C8E2
J 0
(-1525 5200);
DISPLAY 0.617021 (-1525 5200);
PAINT AQUA (-1525 5200);
DISPLAY INVISIBLE (-1525 5200);
FORCEPROP 2 LAST BOM_COST PROC_SIDEBAND
J 0
(-1525 5300);
DISPLAY 1.021277 (-1525 5300);
PAINT ORANGE (-1525 5300);
DISPLAY INVISIBLE (-1525 5300);
FORCEPROP 1 LAST PATH I40
J 0
(-1525 5250);
DISPLAY 0.978723 (-1525 5250);
PAINT WHITE (-1525 5250);
DISPLAY INVISIBLE (-1525 5250);
FORCEPROP 2 LAST SEC 1
J 0
(-1525 5300);
DISPLAY 0.680851 (-1525 5300);
PAINT MONO (-1525 5300);
DISPLAY INVISIBLE (-1525 5300);
FORCEPROP 2 LAST ROOM PROC_SIDEBAND
J 0
(-1525 5250);
DISPLAY 1.021277 (-1525 5250);
PAINT ORANGE (-1525 5250);
DISPLAY INVISIBLE (-1525 5250);
FORCEPROP 2 LAST SEC_TYPE 0402V
J 0
(-1525 5300);
DISPLAY 1.021277 (-1525 5300);
PAINT ORANGE (-1525 5300);
DISPLAY INVISIBLE (-1525 5300);
FORCEPROP 2 LAST CDS_SEC 1
J 0
(-1525 5250);
PAINT ORANGE (-1525 5250);
DISPLAY INVISIBLE (-1525 5250);
FORCEADD GND..1
(-1575 4825);
FORCEPROP 3 LASTPIN (-1575 4875) SIG_NAME GND\g
J 0
(-1565 4885);
DISPLAY 0.659574 (-1565 4885);
PAINT MONO (-1565 4885);
DISPLAY INVISIBLE (-1565 4885);
FORCEPROP 1 LAST BODY_TYPE PLUMBING
J 0
(-1620 4782);
DISPLAY 0.340426 (-1620 4782);
PAINT GREEN (-1620 4782);
DISPLAY INVISIBLE (-1620 4782);
FORCEPROP 1 LAST VOLTAGE 0.0V
J 0
(-1620 4782);
DISPLAY 0.340426 (-1620 4782);
PAINT SKYBLUE (-1620 4782);
DISPLAY INVISIBLE (-1620 4782);
FORCEPROP 2 LAST CDS_LIB mstr_symbols
J 0
(-1575 4825);
PAINT ORANGE (-1575 4825);
DISPLAY INVISIBLE (-1575 4825);
FORCEPROP 1 LAST HDL_POWER GND
J 0
(-1575 4975);
DISPLAY 0.872340 (-1575 4975);
PAINT GREEN (-1575 4975);
DISPLAY INVISIBLE (-1575 4975);
FORCEPROP 1 LAST PATH I41
J 0
(-1500 4825);
DISPLAY 0.872340 (-1500 4825);
PAINT AQUA (-1500 4825);
DISPLAY INVISIBLE (-1500 4825);
FORCEPROP 1 LAST SIZE 1B
J 0
(-1500 4775);
DISPLAY 0.872340 (-1500 4775);
PAINT AQUA (-1500 4775);
DISPLAY INVISIBLE (-1500 4775);
FORCEADD CAP..1
(-3700 4250);
FORCEPROP 1 LAST PACK_TYPE 0402LF
J 0
(-3550 4050);
DISPLAY 0.617021 (-3550 4050);
PAINT SKYBLUE (-3550 4050);
FORCEPROP 1 LASTPIN (-3700 4150) $PN 2
J 0
(-3690 4130);
DISPLAY 0.617021 (-3690 4130);
PAINT ORANGE (-3690 4130);
FORCEPROP 1 LASTPIN (-3700 4350) $PN 1
J 0
(-3690 4330);
DISPLAY 0.617021 (-3690 4330);
PAINT ORANGE (-3690 4330);
FORCEPROP 1 LAST MATERIAL EMPTY
J 0
(-3550 4150);
DISPLAY 0.617021 (-3550 4150);
PAINT RED (-3550 4150);
FORCEPROP 1 LAST LOCATION C8D3
J 0
(-3550 4350);
DISPLAY 0.617021 (-3550 4350);
PAINT AQUA (-3550 4350);
FORCEPROP 1 LAST PART_NUMBER A36096-049
J 0
(-3550 4100);
DISPLAY 0.617021 (-3550 4100);
PAINT BLUE (-3550 4100);
FORCEPROP 1 LAST VALUE 470PF
J 0
(-3550 4300);
DISPLAY 0.617021 (-3550 4300);
PAINT SKYBLUE (-3550 4300);
FORCEPROP 1 LAST TOLERANCE 10%
J 0
(-3550 4200);
DISPLAY 0.617021 (-3550 4200);
PAINT SKYBLUE (-3550 4200);
FORCEPROP 1 LAST VOLTAGE 50V
J 0
(-3550 4250);
DISPLAY 0.617021 (-3550 4250);
PAINT SKYBLUE (-3550 4250);
FORCEPROP 2 LAST CDS_LIB mstr_discrete
J 0
(-3700 4250);
PAINT ORANGE (-3700 4250);
DISPLAY INVISIBLE (-3700 4250);
FORCEPROP 2 LAST ROOM PROC_SIDEBAND
J 0
(-3650 4400);
DISPLAY 1.021277 (-3650 4400);
PAINT ORANGE (-3650 4400);
DISPLAY INVISIBLE (-3650 4400);
FORCEPROP 1 LAST PATH I42
J 0
(-3650 4400);
DISPLAY 0.978723 (-3650 4400);
PAINT WHITE (-3650 4400);
DISPLAY INVISIBLE (-3650 4400);
FORCEPROP 2 LAST SEC 1
J 0
(-3650 4450);
DISPLAY 0.680851 (-3650 4450);
PAINT MONO (-3650 4450);
DISPLAY INVISIBLE (-3650 4450);
FORCEPROP 2 LAST BOM_COST PROC_SIDEBAND
J 0
(-3650 4450);
DISPLAY 1.021277 (-3650 4450);
PAINT ORANGE (-3650 4450);
DISPLAY INVISIBLE (-3650 4450);
FORCEPROP 2 LAST SEC_TYPE 0402LF
J 0
(-3650 4450);
DISPLAY 1.021277 (-3650 4450);
PAINT ORANGE (-3650 4450);
DISPLAY INVISIBLE (-3650 4450);
FORCEPROP 2 LAST CDS_LOCATION C8D3
J 0
(-3550 4350);
DISPLAY 0.617021 (-3550 4350);
PAINT AQUA (-3550 4350);
DISPLAY INVISIBLE (-3550 4350);
FORCEADD GND..1
(-3700 3950);
FORCEPROP 3 LASTPIN (-3700 4000) SIG_NAME GND\g
J 0
(-3690 4010);
DISPLAY 0.659574 (-3690 4010);
PAINT MONO (-3690 4010);
DISPLAY INVISIBLE (-3690 4010);
FORCEPROP 1 LAST VOLTAGE 0.0V
J 0
(-3745 3907);
DISPLAY 0.340426 (-3745 3907);
PAINT SKYBLUE (-3745 3907);
DISPLAY INVISIBLE (-3745 3907);
FORCEPROP 2 LAST CDS_LIB mstr_symbols
J 0
(-3700 3950);
PAINT ORANGE (-3700 3950);
DISPLAY INVISIBLE (-3700 3950);
FORCEPROP 1 LAST SIZE 1B
J 0
(-3625 3900);
DISPLAY 0.872340 (-3625 3900);
PAINT AQUA (-3625 3900);
DISPLAY INVISIBLE (-3625 3900);
FORCEPROP 1 LAST BODY_TYPE PLUMBING
J 0
(-3745 3907);
DISPLAY 0.340426 (-3745 3907);
PAINT GREEN (-3745 3907);
DISPLAY INVISIBLE (-3745 3907);
FORCEPROP 1 LAST PATH I43
J 0
(-3625 3950);
DISPLAY 0.872340 (-3625 3950);
PAINT AQUA (-3625 3950);
DISPLAY INVISIBLE (-3625 3950);
FORCEPROP 1 LAST HDL_POWER GND
J 0
(-3700 4100);
DISPLAY 0.872340 (-3700 4100);
PAINT GREEN (-3700 4100);
DISPLAY INVISIBLE (-3700 4100);
FORCEADD OFFPAGE..1
(-5000 4775);
FORCEPROP 2 LAST $XR0 199 
J 0
(-5252 4775);
DISPLAY 0.638298 (-5252 4775);
PAINT MONO (-5252 4775);
FORCEPROP 2 LAST $XR1 118 
J 0
(-5372 4775);
DISPLAY 0.638298 (-5372 4775);
PAINT MONO (-5372 4775);
FORCEPROP 2 LAST $XR2 146 
J 0
(-5492 4775);
DISPLAY 0.638298 (-5492 4775);
PAINT MONO (-5492 4775);
FORCEPROP 2 LAST PATH I44
J 0
(-5275 4825);
DISPLAY 1.021277 (-5275 4825);
PAINT ORANGE (-5275 4825);
DISPLAY INVISIBLE (-5275 4825);
FORCEPROP 2 LAST CDS_LIB mstr_standard
J 0
(-5000 4775);
PAINT ORANGE (-5000 4775);
DISPLAY INVISIBLE (-5000 4775);
FORCEPROP 1 LAST OFFPAGE TRUE
J 0
(-4675 4650);
DISPLAY 0.872340 (-4675 4650);
PAINT GREEN (-4675 4650);
DISPLAY INVISIBLE (-4675 4650);
FORCEPROP 1 LAST COMMENT_BODY TRUE
J 0
(-4875 4675);
DISPLAY 0.872340 (-4875 4675);
PAINT GREEN (-4875 4675);
DISPLAY INVISIBLE (-4875 4675);
FORCEADD TTL1G07_A..1
(-1400 2525);
FORCEPROP 1 LAST POWER_GROUP VCC=P3V3_STBY;GND=GND
J 1
(-1450 2335);
DISPLAY 0.617021 (-1450 2335);
PAINT ORANGE (-1450 2335);
FORCEPROP 2 LASTPIN (-1500 2525) $PN 2
J 2
(-1510 2535);
DISPLAY 0.617021 (-1510 2535);
PAINT ORANGE (-1510 2535);
FORCEPROP 1 LAST PART_NUMBER C88419-001
J 0
(-1450 2390);
DISPLAY 0.617021 (-1450 2390);
PAINT BLUE (-1450 2390);
FORCEPROP 2 LASTPIN (-1250 2525) $PN 4
J 0
(-1240 2535);
DISPLAY 0.617021 (-1240 2535);
PAINT ORANGE (-1240 2535);
FORCEPROP 1 LAST LOCATION U1R1
J 0
(-1450 2725);
DISPLAY 0.617021 (-1450 2725);
PAINT AQUA (-1450 2725);
FORCEPROP 1 LAST VALUE 74LVC1G07
J 1
(-1400 2625);
DISPLAY 0.617021 (-1400 2625);
PAINT SKYBLUE (-1400 2625);
FORCEPROP 1 LAST MATERIAL IC
J 0
(-1450 2675);
DISPLAY 0.617021 (-1450 2675);
PAINT SKYBLUE (-1450 2675);
FORCEPROP 2 LAST CDS_LIB mstr_ttl
J 0
(-1400 2525);
PAINT MONO (-1400 2525);
DISPLAY INVISIBLE (-1400 2525);
FORCEPROP 0 LAST ROOM FAST_PROCHOT
J 0
(-1450 2825);
DISPLAY 1.021277 (-1450 2825);
PAINT ORANGE (-1450 2825);
DISPLAY INVISIBLE (-1450 2825);
FORCEPROP 1 LAST PATH I46
J 0
(-1350 2575);
DISPLAY 0.978723 (-1350 2575);
PAINT WHITE (-1350 2575);
DISPLAY INVISIBLE (-1350 2575);
FORCEPROP 1 LAST PACK_TYPE SOP
J 0
(-1450 2775);
DISPLAY 0.978723 (-1450 2775);
PAINT SKYBLUE (-1450 2775);
DISPLAY INVISIBLE (-1450 2775);
FORCEPROP 2 LAST CDS_LOCATION U1R1
J 0
(-1450 2725);
DISPLAY 0.617021 (-1450 2725);
PAINT AQUA (-1450 2725);
DISPLAY INVISIBLE (-1450 2725);
FORCEPROP 2 LAST SEC 1
J 0
(-1450 2775);
DISPLAY 0.680851 (-1450 2775);
PAINT MONO (-1450 2775);
DISPLAY INVISIBLE (-1450 2775);
FORCEPROP 2 LAST SEC_TYPE SOP
J 0
(-1450 2775);
DISPLAY 1.021277 (-1450 2775);
PAINT ORANGE (-1450 2775);
DISPLAY INVISIBLE (-1450 2775);
FORCEPROP 0 LAST BOM_COST FAST_PROCHOT
J 0
(-1450 2925);
DISPLAY 1.021277 (-1450 2925);
PAINT ORANGE (-1450 2925);
DISPLAY INVISIBLE (-1450 2925);
FORCEADD OFFPAGE..2
(-50 2525);
FORCEPROP 2 LAST $XR0 119 
J 0
(139 2525);
DISPLAY 0.638298 (139 2525);
PAINT MONO (139 2525);
FORCEPROP 2 LAST $XR1 133 
J 0
(259 2525);
DISPLAY 0.638298 (259 2525);
PAINT MONO (259 2525);
FORCEPROP 2 LAST $XR2 95 
J 0
(379 2525);
DISPLAY 0.638298 (379 2525);
PAINT MONO (379 2525);
FORCEPROP 2 LAST $XR3 120 
J 0
(469 2525);
DISPLAY 0.638298 (469 2525);
PAINT MONO (469 2525);
FORCEPROP 2 LAST $XR4 146 
J 0
(589 2525);
DISPLAY 0.638298 (589 2525);
PAINT MONO (589 2525);
FORCEPROP 2 LAST $XR5 ?
J 0
(589 2525);
DISPLAY 0.638298 (589 2525);
PAINT MONO (589 2525);
FORCEPROP 2 LAST CDS_LIB mstr_standard
J 0
(-50 2525);
PAINT MONO (-50 2525);
DISPLAY INVISIBLE (-50 2525);
FORCEPROP 1 LAST COMMENT_BODY TRUE
J 0
(-95 2430);
DISPLAY 0.872340 (-95 2430);
PAINT GREEN (-95 2430);
DISPLAY INVISIBLE (-95 2430);
FORCEPROP 2 LAST PATH I47
J 0
(0 2600);
DISPLAY 1.021277 (0 2600);
PAINT ORANGE (0 2600);
DISPLAY INVISIBLE (0 2600);
FORCEPROP 1 LAST OFFPAGE TRUE
J 0
(275 2400);
DISPLAY 0.872340 (275 2400);
PAINT GREEN (275 2400);
DISPLAY INVISIBLE (275 2400);
FORCEADD P3V3_STBY..1
(-1600 1950);
FORCEPROP 3 LASTPIN (-1600 1900) SIG_NAME P3V3_STBY\g
J 0
(-1590 1910);
DISPLAY 0.659574 (-1590 1910);
PAINT MONO (-1590 1910);
DISPLAY INVISIBLE (-1590 1910);
FORCEPROP 1 LAST HDL_POWER P3V3_STBY
J 0
(-1900 1825);
DISPLAY 0.872340 (-1900 1825);
PAINT ORANGE (-1900 1825);
DISPLAY INVISIBLE (-1900 1825);
FORCEPROP 1 LAST VOLTAGE 3.3V
J 0
(-1645 1907);
DISPLAY 0.340426 (-1645 1907);
PAINT SKYBLUE (-1645 1907);
DISPLAY INVISIBLE (-1645 1907);
FORCEPROP 1 LAST BODY_TYPE PLUMBING
J 0
(-1645 1907);
DISPLAY 0.340426 (-1645 1907);
PAINT GREEN (-1645 1907);
DISPLAY INVISIBLE (-1645 1907);
FORCEPROP 1 LAST PATH I48
J 0
(-1555 1952);
DISPLAY 0.340426 (-1555 1952);
PAINT GREEN (-1555 1952);
DISPLAY INVISIBLE (-1555 1952);
FORCEPROP 1 LAST SIZE 1B
J 0
(-1555 1972);
DISPLAY 0.340426 (-1555 1972);
PAINT GREEN (-1555 1972);
DISPLAY INVISIBLE (-1555 1972);
FORCEPROP 2 LAST CDS_LIB mstr_symbols
J 0
(-1600 1950);
PAINT ORANGE (-1600 1950);
DISPLAY INVISIBLE (-1600 1950);
FORCEADD CAP_A..1
(-1600 1700);
FORCEPROP 1 LASTPIN (-1600 1600) $PN 2
J 0
(-1590 1580);
DISPLAY 0.617021 (-1590 1580);
PAINT ORANGE (-1590 1580);
FORCEPROP 1 LASTPIN (-1600 1800) $PN 1
J 0
(-1590 1780);
DISPLAY 0.617021 (-1590 1780);
PAINT ORANGE (-1590 1780);
FORCEPROP 1 LAST LOCATION C1R28
J 0
(-1550 1800);
DISPLAY 0.617021 (-1550 1800);
PAINT AQUA (-1550 1800);
FORCEPROP 1 LAST PART_NUMBER A36096-030
J 0
(-1550 1550);
DISPLAY 0.617021 (-1550 1550);
PAINT BLUE (-1550 1550);
FORCEPROP 1 LAST VALUE 0.1UF
J 0
(-1550 1750);
DISPLAY 0.617021 (-1550 1750);
PAINT SKYBLUE (-1550 1750);
FORCEPROP 1 LAST TOLERANCE 10%
J 0
(-1550 1650);
DISPLAY 0.617021 (-1550 1650);
PAINT SKYBLUE (-1550 1650);
FORCEPROP 1 LAST PACK_TYPE 0402V
J 0
(-1550 1500);
DISPLAY 0.617021 (-1550 1500);
PAINT SKYBLUE (-1550 1500);
FORCEPROP 1 LAST VOLTAGE 16V
J 0
(-1550 1700);
DISPLAY 0.617021 (-1550 1700);
PAINT SKYBLUE (-1550 1700);
FORCEPROP 1 LAST MATERIAL X7R
J 0
(-1550 1600);
DISPLAY 0.617021 (-1550 1600);
PAINT SKYBLUE (-1550 1600);
FORCEPROP 2 LAST CDS_LIB dev_discrete
J 0
(-1600 1700);
PAINT ORANGE (-1600 1700);
DISPLAY INVISIBLE (-1600 1700);
FORCEPROP 2 LAST ROOM FAST_PROCHOT
J 0
(-1550 1850);
DISPLAY 1.021277 (-1550 1850);
PAINT ORANGE (-1550 1850);
DISPLAY INVISIBLE (-1550 1850);
FORCEPROP 2 LAST CDS_SEC 1
J 0
(-1550 1850);
PAINT ORANGE (-1550 1850);
DISPLAY INVISIBLE (-1550 1850);
FORCEPROP 2 LAST CDS_LOCATION C1R28
J 0
(-1550 1800);
DISPLAY 0.617021 (-1550 1800);
PAINT AQUA (-1550 1800);
DISPLAY INVISIBLE (-1550 1800);
FORCEPROP 1 LAST PATH I49
J 0
(-1550 1850);
DISPLAY 0.978723 (-1550 1850);
PAINT WHITE (-1550 1850);
DISPLAY INVISIBLE (-1550 1850);
FORCEPROP 2 LAST SEC 1
J 0
(-1550 1900);
DISPLAY 0.680851 (-1550 1900);
PAINT MONO (-1550 1900);
DISPLAY INVISIBLE (-1550 1900);
FORCEPROP 2 LAST SEC_TYPE 0402V
J 0
(-1550 1900);
DISPLAY 1.021277 (-1550 1900);
PAINT ORANGE (-1550 1900);
DISPLAY INVISIBLE (-1550 1900);
FORCEPROP 2 LAST BOM_COST FAST_PROCHOT
J 0
(-1550 1900);
DISPLAY 1.021277 (-1550 1900);
PAINT ORANGE (-1550 1900);
DISPLAY INVISIBLE (-1550 1900);
FORCEADD OFFPAGE..1
(-2525 4425);
FORCEPROP 2 LAST $XR3 ?
J 0
(-3017 4425);
DISPLAY 0.638298 (-3017 4425);
PAINT MONO (-3017 4425);
FORCEPROP 2 LAST $XR0 119 
J 0
(-2777 4425);
DISPLAY 0.638298 (-2777 4425);
PAINT MONO (-2777 4425);
FORCEPROP 2 LAST $XR1 146 
J 0
(-2897 4425);
DISPLAY 0.638298 (-2897 4425);
PAINT MONO (-2897 4425);
FORCEPROP 2 LAST $XR2 120 
J 0
(-3017 4425);
DISPLAY 0.638298 (-3017 4425);
PAINT MONO (-3017 4425);
FORCEPROP 1 LAST COMMENT_BODY TRUE
J 0
(-2400 4325);
DISPLAY 0.872340 (-2400 4325);
PAINT GREEN (-2400 4325);
DISPLAY INVISIBLE (-2400 4325);
FORCEPROP 2 LAST CDS_LIB mstr_standard
J 0
(-2525 4425);
PAINT MONO (-2525 4425);
DISPLAY INVISIBLE (-2525 4425);
FORCEPROP 2 LAST PATH I5
J 0
(-2475 4500);
DISPLAY 1.021277 (-2475 4500);
PAINT ORANGE (-2475 4500);
DISPLAY INVISIBLE (-2475 4500);
FORCEPROP 1 LAST OFFPAGE TRUE
J 0
(-2200 4300);
DISPLAY 0.872340 (-2200 4300);
PAINT GREEN (-2200 4300);
DISPLAY INVISIBLE (-2200 4300);
FORCEADD GND..1
(-1600 1425);
FORCEPROP 3 LASTPIN (-1600 1475) SIG_NAME GND\g
J 0
(-1590 1485);
DISPLAY 0.659574 (-1590 1485);
PAINT MONO (-1590 1485);
DISPLAY INVISIBLE (-1590 1485);
FORCEPROP 1 LAST VOLTAGE 0.0V
J 0
(-1645 1382);
DISPLAY 0.340426 (-1645 1382);
PAINT SKYBLUE (-1645 1382);
DISPLAY INVISIBLE (-1645 1382);
FORCEPROP 1 LAST BODY_TYPE PLUMBING
J 0
(-1645 1382);
DISPLAY 0.340426 (-1645 1382);
PAINT GREEN (-1645 1382);
DISPLAY INVISIBLE (-1645 1382);
FORCEPROP 2 LAST CDS_LIB mstr_symbols
J 0
(-1600 1425);
PAINT ORANGE (-1600 1425);
DISPLAY INVISIBLE (-1600 1425);
FORCEPROP 1 LAST HDL_POWER GND
J 0
(-1600 1575);
DISPLAY 0.872340 (-1600 1575);
PAINT GREEN (-1600 1575);
DISPLAY INVISIBLE (-1600 1575);
FORCEPROP 1 LAST PATH I50
J 0
(-1525 1425);
DISPLAY 0.872340 (-1525 1425);
PAINT AQUA (-1525 1425);
DISPLAY INVISIBLE (-1525 1425);
FORCEPROP 1 LAST SIZE 1B
J 0
(-1525 1375);
DISPLAY 0.872340 (-1525 1375);
PAINT AQUA (-1525 1375);
DISPLAY INVISIBLE (-1525 1375);
FORCEADD RES..1
(-650 2525);
FORCEPROP 1 LAST MATERIAL CHIP
J 0
(-925 2425);
DISPLAY 0.617021 (-925 2425);
PAINT SKYBLUE (-925 2425);
FORCEPROP 1 LAST VALUE 0.0
J 2
(-750 2475);
DISPLAY 0.617021 (-750 2475);
PAINT SKYBLUE (-750 2475);
FORCEPROP 1 LAST PACK_TYPE 0402
J 0
(-775 2425);
DISPLAY 0.617021 (-775 2425);
PAINT SKYBLUE (-775 2425);
FORCEPROP 1 LASTPIN (-550 2525) $PN 2
J 0
(-588 2537);
DISPLAY 0.617021 (-588 2537);
PAINT ORANGE (-588 2537);
FORCEPROP 1 LASTPIN (-750 2525) $PN 1
J 0
(-738 2537);
DISPLAY 0.617021 (-738 2537);
PAINT ORANGE (-738 2537);
FORCEPROP 1 LAST LOCATION R1R8
J 0
(-700 2575);
DISPLAY 0.617021 (-700 2575);
PAINT AQUA (-700 2575);
FORCEPROP 1 LAST PART_NUMBER G21497-005
J 0
(-775 2375);
DISPLAY 0.617021 (-775 2375);
PAINT BLUE (-775 2375);
FORCEPROP 1 LAST TOLERANCE 5%
J 0
(-550 2425);
DISPLAY 0.617021 (-550 2425);
PAINT SKYBLUE (-550 2425);
FORCEPROP 1 LAST WATTAGE 1/16W
J 2
(-500 2475);
DISPLAY 0.617021 (-500 2475);
PAINT SKYBLUE (-500 2475);
FORCEPROP 2 LAST ROOM PROC_SIDEBAND
J 0
(-725 2450);
DISPLAY 0.617021 (-725 2450);
PAINT ORANGE (-725 2450);
DISPLAY INVISIBLE (-725 2450);
FORCEPROP 2 LAST CDS_LIB mstr_discrete
J 0
(-650 2525);
PAINT MONO (-650 2525);
DISPLAY INVISIBLE (-650 2525);
FORCEPROP 2 LAST BOM_COST PROC_SIDEBAND
J 2
(-650 2525);
PAINT MONO (-650 2525);
DISPLAY INVISIBLE (-650 2525);
FORCEPROP 1 LAST PATH I51
J 0
(-700 2675);
DISPLAY 0.978723 (-700 2675);
PAINT WHITE (-700 2675);
DISPLAY INVISIBLE (-700 2675);
FORCEPROP 2 LAST CDS_LOCATION R1R8
J 0
(-700 2575);
DISPLAY 0.617021 (-700 2575);
PAINT AQUA (-700 2575);
DISPLAY INVISIBLE (-700 2575);
FORCEPROP 2 LAST SEC 1
J 0
(-700 2725);
DISPLAY 0.680851 (-700 2725);
PAINT MONO (-700 2725);
DISPLAY INVISIBLE (-700 2725);
FORCEPROP 2 LAST SEC_TYPE 0402
J 0
(-700 2725);
DISPLAY 1.021277 (-700 2725);
PAINT ORANGE (-700 2725);
DISPLAY INVISIBLE (-700 2725);
FORCEADD RES..2
(-3825 5100);
FORCEPROP 1 LAST PACK_TYPE 0402
J 0
(-3785 4925);
DISPLAY 0.617021 (-3785 4925);
PAINT SKYBLUE (-3785 4925);
FORCEPROP 1 LAST MATERIAL CHIP
J 0
(-3785 5025);
DISPLAY 0.617021 (-3785 5025);
PAINT SKYBLUE (-3785 5025);
FORCEPROP 1 LAST WATTAGE 1/16W
J 0
(-3785 5075);
DISPLAY 0.617021 (-3785 5075);
PAINT SKYBLUE (-3785 5075);
FORCEPROP 1 LASTPIN (-3825 5000) $PN 2
J 0
(-3820 5010);
DISPLAY 0.617021 (-3820 5010);
PAINT ORANGE (-3820 5010);
FORCEPROP 1 LAST PART_NUMBER G21497-062
J 0
(-3785 4975);
DISPLAY 0.617021 (-3785 4975);
PAINT BLUE (-3785 4975);
FORCEPROP 1 LAST TOLERANCE 5%
J 0
(-3780 5125);
DISPLAY 0.617021 (-3780 5125);
PAINT SKYBLUE (-3780 5125);
FORCEPROP 1 LASTPIN (-3825 5200) $PN 1
J 0
(-3820 5162);
DISPLAY 0.617021 (-3820 5162);
PAINT ORANGE (-3820 5162);
FORCEPROP 1 LAST VALUE 560
J 0
(-3780 5175);
DISPLAY 0.617021 (-3780 5175);
PAINT SKYBLUE (-3780 5175);
FORCEPROP 1 LAST LOCATION R2P8
J 0
(-3780 5225);
DISPLAY 0.617021 (-3780 5225);
PAINT AQUA (-3780 5225);
FORCEPROP 2 LAST CDS_LIB mstr_discrete
J 0
(-3825 5100);
PAINT ORANGE (-3825 5100);
DISPLAY INVISIBLE (-3825 5100);
FORCEPROP 2 LAST CDS_LOCATION R2P8
J 0
(-3780 5225);
DISPLAY 0.617021 (-3780 5225);
PAINT AQUA (-3780 5225);
DISPLAY INVISIBLE (-3780 5225);
FORCEPROP 2 LAST SEC 1
J 0
(-3775 5325);
DISPLAY 0.680851 (-3775 5325);
PAINT MONO (-3775 5325);
DISPLAY INVISIBLE (-3775 5325);
FORCEPROP 1 LAST PATH I52
J 0
(-3775 5275);
DISPLAY 0.978723 (-3775 5275);
PAINT WHITE (-3775 5275);
DISPLAY INVISIBLE (-3775 5275);
FORCEPROP 0 LAST ROOM PROC_SIDEBAND
J 0
(-3775 5325);
DISPLAY 1.021277 (-3775 5325);
PAINT ORANGE (-3775 5325);
DISPLAY INVISIBLE (-3775 5325);
FORCEPROP 2 LAST SEC_TYPE 0402
J 0
(-3775 5325);
DISPLAY 1.021277 (-3775 5325);
PAINT ORANGE (-3775 5325);
DISPLAY INVISIBLE (-3775 5325);
FORCEPROP 0 LAST BOM_COST PROC_SIDEBAND
J 0
(-3775 5425);
DISPLAY 1.021277 (-3775 5425);
PAINT ORANGE (-3775 5425);
DISPLAY INVISIBLE (-3775 5425);
FORCEADD P3V3_STBY..1
(-3825 5475);
FORCEPROP 3 LASTPIN (-3825 5425) SIG_NAME P3V3_STBY\g
J 0
(-3815 5435);
DISPLAY 0.659574 (-3815 5435);
PAINT MONO (-3815 5435);
DISPLAY INVISIBLE (-3815 5435);
FORCEPROP 1 LAST HDL_POWER P3V3_STBY
J 0
(-4125 5350);
DISPLAY 0.872340 (-4125 5350);
PAINT ORANGE (-4125 5350);
DISPLAY INVISIBLE (-4125 5350);
FORCEPROP 1 LAST VOLTAGE 3.3V
J 0
(-3870 5432);
DISPLAY 0.340426 (-3870 5432);
PAINT SKYBLUE (-3870 5432);
DISPLAY INVISIBLE (-3870 5432);
FORCEPROP 1 LAST BODY_TYPE PLUMBING
J 0
(-3870 5432);
DISPLAY 0.340426 (-3870 5432);
PAINT GREEN (-3870 5432);
DISPLAY INVISIBLE (-3870 5432);
FORCEPROP 1 LAST SIZE 1B
J 0
(-3780 5497);
DISPLAY 0.340426 (-3780 5497);
PAINT GREEN (-3780 5497);
DISPLAY INVISIBLE (-3780 5497);
FORCEPROP 1 LAST PATH I53
J 0
(-3780 5477);
DISPLAY 0.340426 (-3780 5477);
PAINT GREEN (-3780 5477);
DISPLAY INVISIBLE (-3780 5477);
FORCEPROP 2 LAST CDS_LIB mstr_symbols
J 0
(-3825 5475);
PAINT MONO (-3825 5475);
DISPLAY INVISIBLE (-3825 5475);
FORCEADD RES..2
(-3450 2075);
FORCEPROP 1 LASTPIN (-3450 1975) $PN 2
J 0
(-3445 1985);
DISPLAY 0.617021 (-3445 1985);
PAINT ORANGE (-3445 1985);
FORCEPROP 1 LAST PART_NUMBER G21796-072
J 0
(-3410 1950);
DISPLAY 0.617021 (-3410 1950);
PAINT BLUE (-3410 1950);
FORCEPROP 1 LAST PACK_TYPE 0402
J 0
(-3410 1900);
DISPLAY 0.617021 (-3410 1900);
PAINT SKYBLUE (-3410 1900);
FORCEPROP 1 LAST MATERIAL CHIP
J 0
(-3410 2000);
DISPLAY 0.617021 (-3410 2000);
PAINT SKYBLUE (-3410 2000);
FORCEPROP 1 LAST TOLERANCE 1%
J 0
(-3405 2100);
DISPLAY 0.617021 (-3405 2100);
PAINT SKYBLUE (-3405 2100);
FORCEPROP 1 LASTPIN (-3450 2175) $PN 1
J 0
(-3445 2137);
DISPLAY 0.617021 (-3445 2137);
PAINT ORANGE (-3445 2137);
FORCEPROP 1 LAST LOCATION R2T3
J 0
(-3405 2200);
DISPLAY 0.617021 (-3405 2200);
PAINT AQUA (-3405 2200);
FORCEPROP 1 LAST VALUE 4.75K
J 0
(-3405 2150);
DISPLAY 0.617021 (-3405 2150);
PAINT SKYBLUE (-3405 2150);
FORCEPROP 1 LAST WATTAGE 1/16W
J 0
(-3410 2050);
DISPLAY 0.617021 (-3410 2050);
PAINT SKYBLUE (-3410 2050);
FORCEPROP 2 LAST CDS_LIB mstr_discrete
J 0
(-3450 2075);
PAINT MONO (-3450 2075);
DISPLAY INVISIBLE (-3450 2075);
FORCEPROP 2 LAST CDS_LOCATION R2T3
J 0
(-3405 2200);
DISPLAY 0.617021 (-3405 2200);
PAINT AQUA (-3405 2200);
DISPLAY INVISIBLE (-3405 2200);
FORCEPROP 1 LAST PATH I54
J 0
(-3400 2250);
DISPLAY 0.978723 (-3400 2250);
PAINT WHITE (-3400 2250);
DISPLAY INVISIBLE (-3400 2250);
FORCEPROP 0 LAST ROOM FAST_PROCHOT
J 0
(-3400 2300);
DISPLAY 1.021277 (-3400 2300);
PAINT ORANGE (-3400 2300);
DISPLAY INVISIBLE (-3400 2300);
FORCEPROP 2 LAST SEC 1
J 0
(-3400 2300);
DISPLAY 0.680851 (-3400 2300);
PAINT MONO (-3400 2300);
DISPLAY INVISIBLE (-3400 2300);
FORCEPROP 2 LAST SEC_TYPE 0402
J 0
(-3400 2300);
DISPLAY 1.021277 (-3400 2300);
PAINT ORANGE (-3400 2300);
DISPLAY INVISIBLE (-3400 2300);
FORCEPROP 0 LAST BOM_COST FAST_PROCHOT
J 0
(-3400 2400);
DISPLAY 1.021277 (-3400 2400);
PAINT ORANGE (-3400 2400);
DISPLAY INVISIBLE (-3400 2400);
FORCEADD P3V3_STBY..1
(-3450 2350);
FORCEPROP 3 LASTPIN (-3450 2300) SIG_NAME P3V3_STBY\g
J 0
(-3440 2310);
DISPLAY 0.659574 (-3440 2310);
PAINT MONO (-3440 2310);
DISPLAY INVISIBLE (-3440 2310);
FORCEPROP 1 LAST HDL_POWER P3V3_STBY
J 0
(-3750 2225);
DISPLAY 0.872340 (-3750 2225);
PAINT ORANGE (-3750 2225);
DISPLAY INVISIBLE (-3750 2225);
FORCEPROP 1 LAST BODY_TYPE PLUMBING
J 0
(-3495 2307);
DISPLAY 0.340426 (-3495 2307);
PAINT GREEN (-3495 2307);
DISPLAY INVISIBLE (-3495 2307);
FORCEPROP 2 LAST CDS_LIB mstr_symbols
J 0
(-3450 2350);
PAINT MONO (-3450 2350);
DISPLAY INVISIBLE (-3450 2350);
FORCEPROP 1 LAST PATH I55
J 0
(-3405 2352);
DISPLAY 0.340426 (-3405 2352);
PAINT GREEN (-3405 2352);
DISPLAY INVISIBLE (-3405 2352);
FORCEPROP 1 LAST VOLTAGE 3.3V
J 0
(-3495 2307);
DISPLAY 0.340426 (-3495 2307);
PAINT SKYBLUE (-3495 2307);
DISPLAY INVISIBLE (-3495 2307);
FORCEPROP 1 LAST SIZE 1B
J 0
(-3405 2372);
DISPLAY 0.340426 (-3405 2372);
PAINT GREEN (-3405 2372);
DISPLAY INVISIBLE (-3405 2372);
FORCEADD RES..2
(-4150 5100);
FORCEPROP 1 LASTPIN (-4150 5000) $PN 2
J 0
(-4145 5010);
DISPLAY 0.617021 (-4145 5010);
PAINT ORANGE (-4145 5010);
FORCEPROP 1 LASTPIN (-4150 5200) $PN 1
J 0
(-4145 5162);
DISPLAY 0.617021 (-4145 5162);
PAINT ORANGE (-4145 5162);
FORCEPROP 1 LAST PART_NUMBER G21796-072
J 0
(-4110 4975);
DISPLAY 0.617021 (-4110 4975);
PAINT BLUE (-4110 4975);
FORCEPROP 1 LAST PACK_TYPE 0402
J 0
(-4110 4925);
DISPLAY 0.617021 (-4110 4925);
PAINT SKYBLUE (-4110 4925);
FORCEPROP 1 LAST MATERIAL CHIP
J 0
(-4110 5025);
DISPLAY 0.617021 (-4110 5025);
PAINT SKYBLUE (-4110 5025);
FORCEPROP 1 LAST WATTAGE 1/16W
J 0
(-4110 5075);
DISPLAY 0.617021 (-4110 5075);
PAINT SKYBLUE (-4110 5075);
FORCEPROP 1 LAST TOLERANCE 1%
J 0
(-4105 5125);
DISPLAY 0.617021 (-4105 5125);
PAINT SKYBLUE (-4105 5125);
FORCEPROP 1 LAST VALUE 4.75K
J 0
(-4105 5175);
DISPLAY 0.617021 (-4105 5175);
PAINT SKYBLUE (-4105 5175);
FORCEPROP 1 LAST LOCATION R2P5
J 0
(-4105 5225);
DISPLAY 0.617021 (-4105 5225);
PAINT AQUA (-4105 5225);
FORCEPROP 2 LAST CDS_LIB mstr_discrete
J 0
(-4150 5100);
PAINT MONO (-4150 5100);
DISPLAY INVISIBLE (-4150 5100);
FORCEPROP 0 LAST ROOM PROC_SIDEBAND
J 0
(-4100 5325);
DISPLAY 1.021277 (-4100 5325);
PAINT ORANGE (-4100 5325);
DISPLAY INVISIBLE (-4100 5325);
FORCEPROP 1 LAST PATH I56
J 0
(-4100 5275);
DISPLAY 0.978723 (-4100 5275);
PAINT WHITE (-4100 5275);
DISPLAY INVISIBLE (-4100 5275);
FORCEPROP 2 LAST SEC 1
J 0
(-4100 5325);
DISPLAY 0.680851 (-4100 5325);
PAINT MONO (-4100 5325);
DISPLAY INVISIBLE (-4100 5325);
FORCEPROP 2 LAST SEC_TYPE 0402
J 0
(-4100 5325);
DISPLAY 1.021277 (-4100 5325);
PAINT ORANGE (-4100 5325);
DISPLAY INVISIBLE (-4100 5325);
FORCEPROP 0 LAST BOM_COST PROC_SIDEBAND
J 0
(-4100 5325);
DISPLAY 1.021277 (-4100 5325);
PAINT ORANGE (-4100 5325);
DISPLAY INVISIBLE (-4100 5325);
FORCEPROP 2 LAST CDS_LOCATION R2P5
J 0
(-4105 5225);
DISPLAY 0.617021 (-4105 5225);
PAINT AQUA (-4105 5225);
DISPLAY INVISIBLE (-4105 5225);
FORCEADD FET_N..8
(-4150 4225);
FORCEPROP 1 LASTPIN (-4350 4125) $PN 1
J 2
(-4347 4140);
DISPLAY 0.617021 (-4347 4140);
PAINT WHITE (-4347 4140);
FORCEPROP 1 LASTPIN (-4150 4425) $PN 3
J 2
(-4097 4390);
DISPLAY 0.617021 (-4097 4390);
PAINT WHITE (-4097 4390);
FORCEPROP 1 LASTPIN (-4150 4025) $PN 2
J 2
(-4092 4025);
DISPLAY 0.617021 (-4092 4025);
PAINT WHITE (-4092 4025);
FORCEPROP 1 LAST PART_NUMBER C79254-001
J 0
(-3950 4025);
DISPLAY 0.617021 (-3950 4025);
PAINT BLUE (-3950 4025);
FORCEPROP 1 LAST MATERIAL FET
J 0
(-3950 4125);
DISPLAY 0.617021 (-3950 4125);
PAINT SKYBLUE (-3950 4125);
FORCEPROP 1 LAST LOCATION Q2P1
J 0
(-3950 4225);
DISPLAY 0.617021 (-3950 4225);
PAINT AQUA (-3950 4225);
FORCEPROP 1 LAST VALUE 2N7002
J 0
(-3950 4175);
DISPLAY 0.617021 (-3950 4175);
PAINT SKYBLUE (-3950 4175);
FORCEPROP 2 LAST CDS_LIB mstr_discrete
J 0
(-4150 4225);
PAINT MONO (-4150 4225);
DISPLAY INVISIBLE (-4150 4225);
FORCEPROP 1 LAST PACK_TYPE SOT23LF
J 0
(-3950 4075);
DISPLAY 0.978723 (-3950 4075);
PAINT SKYBLUE (-3950 4075);
DISPLAY INVISIBLE (-3950 4075);
FORCEPROP 0 LAST ROOM PROC_SIDEBAND
J 0
(-3950 4325);
DISPLAY 1.021277 (-3950 4325);
PAINT ORANGE (-3950 4325);
DISPLAY INVISIBLE (-3950 4325);
FORCEPROP 1 LAST PATH I58
J 0
(-3950 4275);
DISPLAY 0.978723 (-3950 4275);
PAINT BLUE (-3950 4275);
DISPLAY INVISIBLE (-3950 4275);
FORCEPROP 2 LAST CDS_LOCATION Q2P1
J 0
(-3950 4225);
DISPLAY 0.617021 (-3950 4225);
PAINT AQUA (-3950 4225);
DISPLAY INVISIBLE (-3950 4225);
FORCEPROP 2 LAST SEC 1
J 0
(-3950 4325);
DISPLAY 0.680851 (-3950 4325);
PAINT MONO (-3950 4325);
DISPLAY INVISIBLE (-3950 4325);
FORCEPROP 0 LAST BOM_COST PROC_SIDEBAND
J 0
(-3950 4425);
DISPLAY 1.021277 (-3950 4425);
PAINT ORANGE (-3950 4425);
DISPLAY INVISIBLE (-3950 4425);
FORCEPROP 2 LAST SEC_TYPE SOT23LF
J 0
(-3950 4325);
DISPLAY 1.021277 (-3950 4325);
PAINT ORANGE (-3950 4325);
DISPLAY INVISIBLE (-3950 4325);
FORCEADD OFFPAGE..1
(-5000 4125);
FORCEPROP 2 LAST $XR0 119 
J 0
(-5252 4125);
DISPLAY 0.638298 (-5252 4125);
PAINT MONO (-5252 4125);
FORCEPROP 2 LAST $XR1 145 
J 0
(-5372 4125);
DISPLAY 0.638298 (-5372 4125);
PAINT MONO (-5372 4125);
FORCEPROP 1 LAST OFFPAGE TRUE
J 0
(-4675 4000);
DISPLAY 0.872340 (-4675 4000);
PAINT GREEN (-4675 4000);
DISPLAY INVISIBLE (-4675 4000);
FORCEPROP 1 LAST COMMENT_BODY TRUE
J 0
(-4875 4025);
DISPLAY 0.872340 (-4875 4025);
PAINT GREEN (-4875 4025);
DISPLAY INVISIBLE (-4875 4025);
FORCEPROP 2 LAST CDS_LIB mstr_standard
J 0
(-5000 4125);
PAINT MONO (-5000 4125);
DISPLAY INVISIBLE (-5000 4125);
FORCEPROP 2 LAST PATH I59
J 0
(-4950 4200);
DISPLAY 1.021277 (-4950 4200);
PAINT ORANGE (-4950 4200);
DISPLAY INVISIBLE (-4950 4200);
FORCEADD P3V3_STBY..1
(-5100 3600);
FORCEPROP 3 LASTPIN (-5100 3550) SIG_NAME P3V3_STBY\g
J 0
(-5090 3560);
DISPLAY 0.659574 (-5090 3560);
PAINT MONO (-5090 3560);
DISPLAY INVISIBLE (-5090 3560);
FORCEPROP 1 LAST VOLTAGE 3.3V
J 0
(-5145 3557);
DISPLAY 0.340426 (-5145 3557);
PAINT SKYBLUE (-5145 3557);
DISPLAY INVISIBLE (-5145 3557);
FORCEPROP 1 LAST HDL_POWER P3V3_STBY
J 0
(-5400 3475);
DISPLAY 0.872340 (-5400 3475);
PAINT ORANGE (-5400 3475);
DISPLAY INVISIBLE (-5400 3475);
FORCEPROP 1 LAST BODY_TYPE PLUMBING
J 0
(-5145 3557);
DISPLAY 0.340426 (-5145 3557);
PAINT GREEN (-5145 3557);
DISPLAY INVISIBLE (-5145 3557);
FORCEPROP 1 LAST PATH I6
J 0
(-5055 3602);
DISPLAY 0.340426 (-5055 3602);
PAINT GREEN (-5055 3602);
DISPLAY INVISIBLE (-5055 3602);
FORCEPROP 1 LAST SIZE 1B
J 0
(-5055 3622);
DISPLAY 0.340426 (-5055 3622);
PAINT GREEN (-5055 3622);
DISPLAY INVISIBLE (-5055 3622);
FORCEPROP 2 LAST CDS_LIB mstr_symbols
J 0
(-5100 3600);
PAINT ORANGE (-5100 3600);
DISPLAY INVISIBLE (-5100 3600);
FORCEADD GND..1
(-4150 3900);
FORCEPROP 3 LASTPIN (-4150 3950) SIG_NAME GND\g
J 0
(-4140 3960);
DISPLAY 0.659574 (-4140 3960);
PAINT MONO (-4140 3960);
DISPLAY INVISIBLE (-4140 3960);
FORCEPROP 1 LAST VOLTAGE 0.0V
J 0
(-4195 3857);
DISPLAY 0.340426 (-4195 3857);
PAINT SKYBLUE (-4195 3857);
DISPLAY INVISIBLE (-4195 3857);
FORCEPROP 2 LAST CDS_LIB mstr_symbols
J 0
(-4150 3900);
PAINT MONO (-4150 3900);
DISPLAY INVISIBLE (-4150 3900);
FORCEPROP 1 LAST BODY_TYPE PLUMBING
J 0
(-4195 3857);
DISPLAY 0.340426 (-4195 3857);
PAINT GREEN (-4195 3857);
DISPLAY INVISIBLE (-4195 3857);
FORCEPROP 1 LAST HDL_POWER GND
J 0
(-4150 4050);
DISPLAY 0.872340 (-4150 4050);
PAINT GREEN (-4150 4050);
DISPLAY INVISIBLE (-4150 4050);
FORCEPROP 1 LAST SIZE 1B
J 0
(-4075 3850);
DISPLAY 0.872340 (-4075 3850);
PAINT AQUA (-4075 3850);
DISPLAY INVISIBLE (-4075 3850);
FORCEPROP 1 LAST PATH I60
J 0
(-4075 3900);
DISPLAY 0.872340 (-4075 3900);
PAINT AQUA (-4075 3900);
DISPLAY INVISIBLE (-4075 3900);
FORCEADD RES..2
(-4600 4350);
FORCEPROP 1 LASTPIN (-4600 4250) $PN 2
J 0
(-4595 4260);
DISPLAY 0.617021 (-4595 4260);
PAINT ORANGE (-4595 4260);
FORCEPROP 1 LAST PACK_TYPE 0402
J 0
(-4560 4175);
DISPLAY 0.617021 (-4560 4175);
PAINT SKYBLUE (-4560 4175);
FORCEPROP 1 LAST MATERIAL CHIP
J 0
(-4560 4275);
DISPLAY 0.617021 (-4560 4275);
PAINT SKYBLUE (-4560 4275);
FORCEPROP 1 LAST WATTAGE 1/16W
J 0
(-4560 4325);
DISPLAY 0.617021 (-4560 4325);
PAINT SKYBLUE (-4560 4325);
FORCEPROP 1 LAST TOLERANCE 1%
J 0
(-4555 4375);
DISPLAY 0.617021 (-4555 4375);
PAINT SKYBLUE (-4555 4375);
FORCEPROP 1 LASTPIN (-4600 4450) $PN 1
J 0
(-4595 4412);
DISPLAY 0.617021 (-4595 4412);
PAINT ORANGE (-4595 4412);
FORCEPROP 1 LAST LOCATION R2P13
J 0
(-4555 4475);
DISPLAY 0.617021 (-4555 4475);
PAINT AQUA (-4555 4475);
FORCEPROP 1 LAST VALUE 4.75K
J 0
(-4555 4425);
DISPLAY 0.617021 (-4555 4425);
PAINT SKYBLUE (-4555 4425);
FORCEPROP 1 LAST PART_NUMBER G21796-072
J 0
(-4560 4225);
DISPLAY 0.617021 (-4560 4225);
PAINT BLUE (-4560 4225);
FORCEPROP 2 LAST CDS_LIB mstr_discrete
J 0
(-4600 4350);
PAINT MONO (-4600 4350);
DISPLAY INVISIBLE (-4600 4350);
FORCEPROP 2 LAST CDS_LOCATION R2P13
J 0
(-4555 4475);
DISPLAY 0.617021 (-4555 4475);
PAINT AQUA (-4555 4475);
DISPLAY INVISIBLE (-4555 4475);
FORCEPROP 1 LAST PATH I61
J 0
(-4550 4525);
DISPLAY 0.978723 (-4550 4525);
PAINT WHITE (-4550 4525);
DISPLAY INVISIBLE (-4550 4525);
FORCEPROP 2 LAST SEC 1
J 0
(-4550 4575);
DISPLAY 0.680851 (-4550 4575);
PAINT MONO (-4550 4575);
DISPLAY INVISIBLE (-4550 4575);
FORCEPROP 0 LAST ROOM PROC_SIDEBAND
J 0
(-4550 4575);
DISPLAY 1.021277 (-4550 4575);
PAINT ORANGE (-4550 4575);
DISPLAY INVISIBLE (-4550 4575);
FORCEPROP 2 LAST SEC_TYPE 0402
J 0
(-4550 4575);
DISPLAY 1.021277 (-4550 4575);
PAINT ORANGE (-4550 4575);
DISPLAY INVISIBLE (-4550 4575);
FORCEPROP 0 LAST BOM_COST PROC_SIDEBAND
J 0
(-4550 4675);
DISPLAY 1.021277 (-4550 4675);
PAINT ORANGE (-4550 4675);
DISPLAY INVISIBLE (-4550 4675);
FORCEADD P3V3_STBY..1
(-4600 4575);
FORCEPROP 3 LASTPIN (-4600 4525) SIG_NAME P3V3_STBY\g
J 0
(-4590 4535);
DISPLAY 0.659574 (-4590 4535);
PAINT MONO (-4590 4535);
DISPLAY INVISIBLE (-4590 4535);
FORCEPROP 1 LAST VOLTAGE 3.3V
J 0
(-4645 4532);
DISPLAY 0.340426 (-4645 4532);
PAINT SKYBLUE (-4645 4532);
DISPLAY INVISIBLE (-4645 4532);
FORCEPROP 1 LAST HDL_POWER P3V3_STBY
J 0
(-4900 4450);
DISPLAY 0.872340 (-4900 4450);
PAINT ORANGE (-4900 4450);
DISPLAY INVISIBLE (-4900 4450);
FORCEPROP 1 LAST BODY_TYPE PLUMBING
J 0
(-4645 4532);
DISPLAY 0.340426 (-4645 4532);
PAINT GREEN (-4645 4532);
DISPLAY INVISIBLE (-4645 4532);
FORCEPROP 1 LAST PATH I62
J 0
(-4555 4577);
DISPLAY 0.340426 (-4555 4577);
PAINT GREEN (-4555 4577);
DISPLAY INVISIBLE (-4555 4577);
FORCEPROP 2 LAST CDS_LIB mstr_symbols
J 0
(-4600 4575);
PAINT MONO (-4600 4575);
DISPLAY INVISIBLE (-4600 4575);
FORCEPROP 1 LAST SIZE 1B
J 0
(-4555 4597);
DISPLAY 0.340426 (-4555 4597);
PAINT GREEN (-4555 4597);
DISPLAY INVISIBLE (-4555 4597);
FORCEADD RES..2
(-4525 3925);
FORCEPROP 1 LAST PACK_TYPE 0402
J 0
(-4485 3750);
DISPLAY 0.617021 (-4485 3750);
PAINT SKYBLUE (-4485 3750);
FORCEPROP 1 LAST TOLERANCE 1%
J 0
(-4480 3950);
DISPLAY 0.617021 (-4480 3950);
PAINT SKYBLUE (-4480 3950);
FORCEPROP 1 LAST MATERIAL EMPTY
J 0
(-4485 3850);
DISPLAY 0.617021 (-4485 3850);
PAINT RED (-4485 3850);
FORCEPROP 1 LAST LOCATION R2P11
J 0
(-4480 4050);
DISPLAY 0.617021 (-4480 4050);
PAINT AQUA (-4480 4050);
FORCEPROP 1 LAST PART_NUMBER G21796-026
J 0
(-4485 3800);
DISPLAY 0.617021 (-4485 3800);
PAINT BLUE (-4485 3800);
FORCEPROP 1 LAST VALUE 1.00K
J 0
(-4480 4000);
DISPLAY 0.617021 (-4480 4000);
PAINT SKYBLUE (-4480 4000);
FORCEPROP 1 LAST WATTAGE 1/16W
J 0
(-4485 3900);
DISPLAY 0.617021 (-4485 3900);
PAINT SKYBLUE (-4485 3900);
FORCEPROP 1 LASTPIN (-4525 3825) $PN 2
J 0
(-4520 3835);
DISPLAY 0.787234 (-4520 3835);
PAINT ORANGE (-4520 3835);
DISPLAY INVISIBLE (-4520 3835);
FORCEPROP 2 LAST CDS_LIB mstr_discrete
J 0
(-4525 3925);
PAINT MONO (-4525 3925);
DISPLAY INVISIBLE (-4525 3925);
FORCEPROP 1 LASTPIN (-4525 4025) $PN 1
J 0
(-4520 3987);
DISPLAY 0.787234 (-4520 3987);
PAINT ORANGE (-4520 3987);
DISPLAY INVISIBLE (-4520 3987);
FORCEPROP 2 LAST CDS_LOCATION R2P11
J 0
(-4480 4050);
DISPLAY 0.617021 (-4480 4050);
PAINT AQUA (-4480 4050);
DISPLAY INVISIBLE (-4480 4050);
FORCEPROP 0 LAST ROOM PROC_SIDEBAND
J 0
(-4475 4150);
DISPLAY 1.021277 (-4475 4150);
PAINT ORANGE (-4475 4150);
DISPLAY INVISIBLE (-4475 4150);
FORCEPROP 1 LAST PATH I63
J 0
(-4475 4100);
DISPLAY 0.978723 (-4475 4100);
PAINT WHITE (-4475 4100);
DISPLAY INVISIBLE (-4475 4100);
FORCEPROP 2 LAST $SEC 1
J 0
(-4475 4150);
PAINT MONO (-4475 4150);
DISPLAY INVISIBLE (-4475 4150);
FORCEPROP 2 LAST CDS_SEC 1
J 0
(-4475 4150);
PAINT MONO (-4475 4150);
DISPLAY INVISIBLE (-4475 4150);
FORCEPROP 0 LAST BOM_COST PROC_SIDEBAND
J 0
(-4475 4250);
DISPLAY 1.021277 (-4475 4250);
PAINT ORANGE (-4475 4250);
DISPLAY INVISIBLE (-4475 4250);
FORCEADD GND..1
(-4525 3700);
FORCEPROP 3 LASTPIN (-4525 3750) SIG_NAME GND\g
J 0
(-4515 3760);
DISPLAY 0.659574 (-4515 3760);
PAINT MONO (-4515 3760);
DISPLAY INVISIBLE (-4515 3760);
FORCEPROP 1 LAST VOLTAGE 0.0V
J 0
(-4570 3657);
DISPLAY 0.340426 (-4570 3657);
PAINT SKYBLUE (-4570 3657);
DISPLAY INVISIBLE (-4570 3657);
FORCEPROP 1 LAST BODY_TYPE PLUMBING
J 0
(-4570 3657);
DISPLAY 0.340426 (-4570 3657);
PAINT GREEN (-4570 3657);
DISPLAY INVISIBLE (-4570 3657);
FORCEPROP 2 LAST CDS_LIB mstr_symbols
J 0
(-4525 3700);
PAINT MONO (-4525 3700);
DISPLAY INVISIBLE (-4525 3700);
FORCEPROP 1 LAST PATH I64
J 0
(-4450 3700);
DISPLAY 0.872340 (-4450 3700);
PAINT AQUA (-4450 3700);
DISPLAY INVISIBLE (-4450 3700);
FORCEPROP 1 LAST SIZE 1B
J 0
(-4450 3650);
DISPLAY 0.872340 (-4450 3650);
PAINT AQUA (-4450 3650);
DISPLAY INVISIBLE (-4450 3650);
FORCEPROP 1 LAST HDL_POWER GND
J 0
(-4525 3850);
DISPLAY 0.872340 (-4525 3850);
PAINT GREEN (-4525 3850);
DISPLAY INVISIBLE (-4525 3850);
FORCEADD RES..2
(-2950 2775);
FORCEPROP 1 LASTPIN (-2950 2675) $PN 2
J 0
(-2945 2685);
DISPLAY 0.617021 (-2945 2685);
PAINT ORANGE (-2945 2685);
FORCEPROP 1 LAST TOLERANCE 1%
J 0
(-2905 2800);
DISPLAY 0.617021 (-2905 2800);
PAINT SKYBLUE (-2905 2800);
FORCEPROP 1 LASTPIN (-2950 2875) $PN 1
J 0
(-2945 2837);
DISPLAY 0.617021 (-2945 2837);
PAINT ORANGE (-2945 2837);
FORCEPROP 1 LAST LOCATION R9F3
J 0
(-2905 2900);
DISPLAY 0.617021 (-2905 2900);
PAINT AQUA (-2905 2900);
FORCEPROP 1 LAST PART_NUMBER G21796-072
J 0
(-2910 2650);
DISPLAY 0.617021 (-2910 2650);
PAINT BLUE (-2910 2650);
FORCEPROP 1 LAST VALUE 4.75K
J 0
(-2905 2850);
DISPLAY 0.617021 (-2905 2850);
PAINT SKYBLUE (-2905 2850);
FORCEPROP 1 LAST PACK_TYPE 0402
J 0
(-2910 2600);
DISPLAY 0.617021 (-2910 2600);
PAINT SKYBLUE (-2910 2600);
FORCEPROP 1 LAST MATERIAL CHIP
J 0
(-2910 2700);
DISPLAY 0.617021 (-2910 2700);
PAINT SKYBLUE (-2910 2700);
FORCEPROP 1 LAST WATTAGE 1/16W
J 0
(-2910 2750);
DISPLAY 0.617021 (-2910 2750);
PAINT SKYBLUE (-2910 2750);
FORCEPROP 2 LAST CDS_LIB mstr_discrete
J 0
(-2950 2775);
PAINT MONO (-2950 2775);
DISPLAY INVISIBLE (-2950 2775);
FORCEPROP 1 LAST PATH I65
J 0
(-2900 2950);
DISPLAY 0.978723 (-2900 2950);
PAINT WHITE (-2900 2950);
DISPLAY INVISIBLE (-2900 2950);
FORCEPROP 2 LAST SEC 1
J 0
(-2900 3000);
DISPLAY 0.680851 (-2900 3000);
PAINT MONO (-2900 3000);
DISPLAY INVISIBLE (-2900 3000);
FORCEPROP 2 LAST CDS_LOCATION R9F3
J 0
(-2905 2900);
DISPLAY 0.617021 (-2905 2900);
PAINT AQUA (-2905 2900);
DISPLAY INVISIBLE (-2905 2900);
FORCEPROP 0 LAST ROOM PROC_SIDEBAND
J 0
(-2900 3000);
DISPLAY 1.021277 (-2900 3000);
PAINT ORANGE (-2900 3000);
DISPLAY INVISIBLE (-2900 3000);
FORCEPROP 0 LAST BOM_COST PROC_SIDEBAND
J 0
(-2900 3000);
DISPLAY 1.021277 (-2900 3000);
PAINT ORANGE (-2900 3000);
DISPLAY INVISIBLE (-2900 3000);
FORCEPROP 2 LAST SEC_TYPE 0402
J 0
(-2900 3000);
DISPLAY 1.021277 (-2900 3000);
PAINT ORANGE (-2900 3000);
DISPLAY INVISIBLE (-2900 3000);
FORCEADD P3V3_STBY..1
(-2950 3000);
FORCEPROP 3 LASTPIN (-2950 2950) SIG_NAME P3V3_STBY\g
J 0
(-2940 2960);
DISPLAY 0.659574 (-2940 2960);
PAINT MONO (-2940 2960);
DISPLAY INVISIBLE (-2940 2960);
FORCEPROP 1 LAST HDL_POWER P3V3_STBY
J 0
(-3250 2875);
DISPLAY 0.872340 (-3250 2875);
PAINT ORANGE (-3250 2875);
DISPLAY INVISIBLE (-3250 2875);
FORCEPROP 1 LAST VOLTAGE 3.3V
J 0
(-2995 2957);
DISPLAY 0.340426 (-2995 2957);
PAINT SKYBLUE (-2995 2957);
DISPLAY INVISIBLE (-2995 2957);
FORCEPROP 2 LAST CDS_LIB mstr_symbols
J 0
(-2950 3000);
PAINT MONO (-2950 3000);
DISPLAY INVISIBLE (-2950 3000);
FORCEPROP 1 LAST BODY_TYPE PLUMBING
J 0
(-2995 2957);
DISPLAY 0.340426 (-2995 2957);
PAINT GREEN (-2995 2957);
DISPLAY INVISIBLE (-2995 2957);
FORCEPROP 1 LAST SIZE 1B
J 0
(-2905 3022);
DISPLAY 0.340426 (-2905 3022);
PAINT GREEN (-2905 3022);
DISPLAY INVISIBLE (-2905 3022);
FORCEPROP 1 LAST PATH I66
J 0
(-2905 3002);
DISPLAY 0.340426 (-2905 3002);
PAINT GREEN (-2905 3002);
DISPLAY INVISIBLE (-2905 3002);
FORCEADD FET_N..8
(-2950 1900);
FORCEPROP 1 LASTPIN (-3150 1800) $PN 1
J 2
(-3147 1815);
DISPLAY 0.617021 (-3147 1815);
PAINT WHITE (-3147 1815);
FORCEPROP 1 LASTPIN (-2950 1700) $PN 2
J 2
(-2892 1700);
DISPLAY 0.617021 (-2892 1700);
PAINT WHITE (-2892 1700);
FORCEPROP 1 LAST LOCATION Q8F2
J 0
(-2750 1900);
DISPLAY 0.617021 (-2750 1900);
PAINT AQUA (-2750 1900);
FORCEPROP 1 LAST VALUE 2N7002
J 0
(-2750 1850);
DISPLAY 0.617021 (-2750 1850);
PAINT SKYBLUE (-2750 1850);
FORCEPROP 1 LAST MATERIAL FET
J 0
(-2750 1800);
DISPLAY 0.617021 (-2750 1800);
PAINT SKYBLUE (-2750 1800);
FORCEPROP 1 LAST PART_NUMBER C79254-001
J 0
(-2750 1700);
DISPLAY 0.617021 (-2750 1700);
PAINT BLUE (-2750 1700);
FORCEPROP 1 LASTPIN (-2950 2100) $PN 3
J 2
(-2897 2065);
DISPLAY 0.617021 (-2897 2065);
PAINT WHITE (-2897 2065);
FORCEPROP 2 LAST CDS_LIB mstr_discrete
J 0
(-2950 1900);
PAINT MONO (-2950 1900);
DISPLAY INVISIBLE (-2950 1900);
FORCEPROP 1 LAST PACK_TYPE SOT23LF
J 0
(-2750 1750);
DISPLAY 0.978723 (-2750 1750);
PAINT SKYBLUE (-2750 1750);
DISPLAY INVISIBLE (-2750 1750);
FORCEPROP 0 LAST ROOM PROC_SIDEBAND
J 0
(-2750 2000);
DISPLAY 1.021277 (-2750 2000);
PAINT ORANGE (-2750 2000);
DISPLAY INVISIBLE (-2750 2000);
FORCEPROP 1 LAST PATH I67
J 0
(-2750 1950);
DISPLAY 0.978723 (-2750 1950);
PAINT BLUE (-2750 1950);
DISPLAY INVISIBLE (-2750 1950);
FORCEPROP 2 LAST CDS_LOCATION Q8F2
J 0
(-2750 1900);
DISPLAY 0.617021 (-2750 1900);
PAINT AQUA (-2750 1900);
DISPLAY INVISIBLE (-2750 1900);
FORCEPROP 2 LAST SEC 1
J 0
(-2750 2000);
DISPLAY 0.680851 (-2750 2000);
PAINT MONO (-2750 2000);
DISPLAY INVISIBLE (-2750 2000);
FORCEPROP 2 LAST SEC_TYPE SOT23LF
J 0
(-2750 2000);
DISPLAY 1.021277 (-2750 2000);
PAINT ORANGE (-2750 2000);
DISPLAY INVISIBLE (-2750 2000);
FORCEPROP 0 LAST BOM_COST PROC_SIDEBAND
J 0
(-2750 2100);
DISPLAY 1.021277 (-2750 2100);
PAINT ORANGE (-2750 2100);
DISPLAY INVISIBLE (-2750 2100);
FORCEADD GND..1
(-2950 1575);
FORCEPROP 3 LASTPIN (-2950 1625) SIG_NAME GND\g
J 0
(-2940 1635);
DISPLAY 0.659574 (-2940 1635);
PAINT MONO (-2940 1635);
DISPLAY INVISIBLE (-2940 1635);
FORCEPROP 1 LAST VOLTAGE 0.0V
J 0
(-2995 1532);
DISPLAY 0.340426 (-2995 1532);
PAINT SKYBLUE (-2995 1532);
DISPLAY INVISIBLE (-2995 1532);
FORCEPROP 1 LAST BODY_TYPE PLUMBING
J 0
(-2995 1532);
DISPLAY 0.340426 (-2995 1532);
PAINT GREEN (-2995 1532);
DISPLAY INVISIBLE (-2995 1532);
FORCEPROP 1 LAST SIZE 1B
J 0
(-2875 1525);
DISPLAY 0.872340 (-2875 1525);
PAINT AQUA (-2875 1525);
DISPLAY INVISIBLE (-2875 1525);
FORCEPROP 1 LAST HDL_POWER GND
J 0
(-2950 1725);
DISPLAY 0.872340 (-2950 1725);
PAINT GREEN (-2950 1725);
DISPLAY INVISIBLE (-2950 1725);
FORCEPROP 2 LAST CDS_LIB mstr_symbols
J 0
(-2950 1575);
PAINT MONO (-2950 1575);
DISPLAY INVISIBLE (-2950 1575);
FORCEPROP 1 LAST PATH I68
J 0
(-2875 1575);
DISPLAY 0.872340 (-2875 1575);
PAINT AQUA (-2875 1575);
DISPLAY INVISIBLE (-2875 1575);
FORCEADD OFFPAGE..1
(-4000 1800);
FORCEPROP 2 LAST $XR0 119 
J 0
(-4252 1800);
DISPLAY 0.638298 (-4252 1800);
PAINT MONO (-4252 1800);
FORCEPROP 2 LAST $XR1 144 
J 0
(-4372 1800);
DISPLAY 0.638298 (-4372 1800);
PAINT MONO (-4372 1800);
FORCEPROP 2 LAST CDS_LIB mstr_standard
J 0
(-4000 1800);
PAINT MONO (-4000 1800);
DISPLAY INVISIBLE (-4000 1800);
FORCEPROP 1 LAST OFFPAGE TRUE
J 0
(-3675 1675);
DISPLAY 0.872340 (-3675 1675);
PAINT GREEN (-3675 1675);
DISPLAY INVISIBLE (-3675 1675);
FORCEPROP 1 LAST COMMENT_BODY TRUE
J 0
(-3875 1700);
DISPLAY 0.872340 (-3875 1700);
PAINT GREEN (-3875 1700);
DISPLAY INVISIBLE (-3875 1700);
FORCEPROP 2 LAST PATH I69
J 0
(-3950 1875);
DISPLAY 1.021277 (-3950 1875);
PAINT ORANGE (-3950 1875);
DISPLAY INVISIBLE (-3950 1875);
FORCEADD GND..1
(-5100 3075);
FORCEPROP 3 LASTPIN (-5100 3125) SIG_NAME GND\g
J 0
(-5090 3135);
DISPLAY 0.659574 (-5090 3135);
PAINT MONO (-5090 3135);
DISPLAY INVISIBLE (-5090 3135);
FORCEPROP 1 LAST VOLTAGE 0.0V
J 0
(-5145 3032);
DISPLAY 0.340426 (-5145 3032);
PAINT SKYBLUE (-5145 3032);
DISPLAY INVISIBLE (-5145 3032);
FORCEPROP 1 LAST BODY_TYPE PLUMBING
J 0
(-5145 3032);
DISPLAY 0.340426 (-5145 3032);
PAINT GREEN (-5145 3032);
DISPLAY INVISIBLE (-5145 3032);
FORCEPROP 1 LAST SIZE 1B
J 0
(-5025 3025);
DISPLAY 0.872340 (-5025 3025);
PAINT AQUA (-5025 3025);
DISPLAY INVISIBLE (-5025 3025);
FORCEPROP 1 LAST HDL_POWER GND
J 0
(-5100 3225);
DISPLAY 0.872340 (-5100 3225);
PAINT GREEN (-5100 3225);
DISPLAY INVISIBLE (-5100 3225);
FORCEPROP 2 LAST CDS_LIB mstr_symbols
J 0
(-5100 3075);
PAINT ORANGE (-5100 3075);
DISPLAY INVISIBLE (-5100 3075);
FORCEPROP 1 LAST PATH I7
J 0
(-5025 3075);
DISPLAY 0.872340 (-5025 3075);
PAINT AQUA (-5025 3075);
DISPLAY INVISIBLE (-5025 3075);
FORCEADD P3V3_STBY..1
(-3150 5475);
FORCEPROP 3 LASTPIN (-3150 5425) SIG_NAME P3V3_STBY\g
J 0
(-3140 5435);
DISPLAY 0.659574 (-3140 5435);
PAINT MONO (-3140 5435);
DISPLAY INVISIBLE (-3140 5435);
FORCEPROP 1 LAST HDL_POWER P3V3_STBY
J 0
(-3450 5350);
DISPLAY 0.872340 (-3450 5350);
PAINT ORANGE (-3450 5350);
DISPLAY INVISIBLE (-3450 5350);
FORCEPROP 1 LAST PATH I70
J 0
(-3105 5477);
DISPLAY 0.340426 (-3105 5477);
PAINT GREEN (-3105 5477);
DISPLAY INVISIBLE (-3105 5477);
FORCEPROP 1 LAST BODY_TYPE PLUMBING
J 0
(-3195 5432);
DISPLAY 0.340426 (-3195 5432);
PAINT GREEN (-3195 5432);
DISPLAY INVISIBLE (-3195 5432);
FORCEPROP 2 LAST CDS_LIB mstr_symbols
J 0
(-3150 5475);
PAINT ORANGE (-3150 5475);
DISPLAY INVISIBLE (-3150 5475);
FORCEPROP 1 LAST SIZE 1B
J 0
(-3105 5497);
DISPLAY 0.340426 (-3105 5497);
PAINT GREEN (-3105 5497);
DISPLAY INVISIBLE (-3105 5497);
FORCEPROP 1 LAST VOLTAGE 3.3V
J 0
(-3195 5432);
DISPLAY 0.340426 (-3195 5432);
PAINT SKYBLUE (-3195 5432);
DISPLAY INVISIBLE (-3195 5432);
FORCEADD RES..2
(-3150 5100);
FORCEPROP 1 LASTPIN (-3150 5000) $PN 2
J 0
(-3145 5010);
DISPLAY 0.617021 (-3145 5010);
PAINT ORANGE (-3145 5010);
FORCEPROP 1 LASTPIN (-3150 5200) $PN 1
J 0
(-3145 5162);
DISPLAY 0.617021 (-3145 5162);
PAINT ORANGE (-3145 5162);
FORCEPROP 1 LAST PACK_TYPE 0402
J 0
(-3110 4925);
DISPLAY 0.617021 (-3110 4925);
PAINT SKYBLUE (-3110 4925);
FORCEPROP 1 LAST PART_NUMBER G21796-072
J 0
(-3110 4975);
DISPLAY 0.617021 (-3110 4975);
PAINT BLUE (-3110 4975);
FORCEPROP 1 LAST MATERIAL CHIP
J 0
(-3110 5025);
DISPLAY 0.617021 (-3110 5025);
PAINT SKYBLUE (-3110 5025);
FORCEPROP 1 LAST WATTAGE 1/16W
J 0
(-3110 5075);
DISPLAY 0.617021 (-3110 5075);
PAINT SKYBLUE (-3110 5075);
FORCEPROP 1 LAST TOLERANCE 1%
J 0
(-3105 5125);
DISPLAY 0.617021 (-3105 5125);
PAINT SKYBLUE (-3105 5125);
FORCEPROP 1 LAST VALUE 4.75K
J 0
(-3105 5175);
DISPLAY 0.617021 (-3105 5175);
PAINT SKYBLUE (-3105 5175);
FORCEPROP 1 LAST LOCATION R8D26
J 0
(-3105 5225);
DISPLAY 0.617021 (-3105 5225);
PAINT AQUA (-3105 5225);
FORCEPROP 2 LAST CDS_LIB mstr_discrete
J 0
(-3150 5100);
PAINT MONO (-3150 5100);
DISPLAY INVISIBLE (-3150 5100);
FORCEPROP 2 LAST ROOM FAST_PROCHOT
J 0
(-3100 5275);
DISPLAY 1.021277 (-3100 5275);
PAINT ORANGE (-3100 5275);
DISPLAY INVISIBLE (-3100 5275);
FORCEPROP 2 LAST SEC_TYPE 0402
J 0
(-3100 5325);
DISPLAY 1.021277 (-3100 5325);
PAINT ORANGE (-3100 5325);
DISPLAY INVISIBLE (-3100 5325);
FORCEPROP 2 LAST BOM_COST FAST_PROCHOT
J 0
(-3100 5325);
DISPLAY 1.021277 (-3100 5325);
PAINT ORANGE (-3100 5325);
DISPLAY INVISIBLE (-3100 5325);
FORCEPROP 2 LAST SEC 1
J 0
(-3100 5325);
PAINT MONO (-3100 5325);
DISPLAY INVISIBLE (-3100 5325);
FORCEPROP 1 LAST PATH I71
J 0
(-3100 5275);
DISPLAY 0.978723 (-3100 5275);
PAINT WHITE (-3100 5275);
DISPLAY INVISIBLE (-3100 5275);
FORCEPROP 2 LAST CDS_LOCATION R8D26
J 0
(-3105 5225);
DISPLAY 0.617021 (-3105 5225);
PAINT AQUA (-3105 5225);
DISPLAY INVISIBLE (-3105 5225);
FORCEADD P3V3_STBY..1
(-2025 3075);
FORCEPROP 3 LASTPIN (-2025 3025) SIG_NAME P3V3_STBY\g
J 0
(-2015 3035);
DISPLAY 0.659574 (-2015 3035);
PAINT MONO (-2015 3035);
DISPLAY INVISIBLE (-2015 3035);
FORCEPROP 1 LAST VOLTAGE 3.3V
J 0
(-2070 3032);
DISPLAY 0.340426 (-2070 3032);
PAINT SKYBLUE (-2070 3032);
DISPLAY INVISIBLE (-2070 3032);
FORCEPROP 1 LAST HDL_POWER P3V3_STBY
J 0
(-2325 2950);
DISPLAY 0.872340 (-2325 2950);
PAINT ORANGE (-2325 2950);
DISPLAY INVISIBLE (-2325 2950);
FORCEPROP 1 LAST BODY_TYPE PLUMBING
J 0
(-2070 3032);
DISPLAY 0.340426 (-2070 3032);
PAINT GREEN (-2070 3032);
DISPLAY INVISIBLE (-2070 3032);
FORCEPROP 1 LAST PATH I72
J 0
(-1980 3077);
DISPLAY 0.340426 (-1980 3077);
PAINT GREEN (-1980 3077);
DISPLAY INVISIBLE (-1980 3077);
FORCEPROP 1 LAST SIZE 1B
J 0
(-1980 3097);
DISPLAY 0.340426 (-1980 3097);
PAINT GREEN (-1980 3097);
DISPLAY INVISIBLE (-1980 3097);
FORCEPROP 2 LAST CDS_LIB mstr_symbols
J 0
(-2025 3075);
PAINT ORANGE (-2025 3075);
DISPLAY INVISIBLE (-2025 3075);
FORCEADD RES..2
(-2025 2850);
FORCEPROP 1 LASTPIN (-2025 2750) $PN 2
J 0
(-2020 2760);
DISPLAY 0.617021 (-2020 2760);
PAINT ORANGE (-2020 2760);
FORCEPROP 1 LAST MATERIAL CHIP
J 0
(-1985 2775);
DISPLAY 0.617021 (-1985 2775);
PAINT SKYBLUE (-1985 2775);
FORCEPROP 1 LAST PACK_TYPE 0402
J 0
(-1985 2675);
DISPLAY 0.617021 (-1985 2675);
PAINT SKYBLUE (-1985 2675);
FORCEPROP 1 LAST TOLERANCE 1%
J 0
(-1980 2875);
DISPLAY 0.617021 (-1980 2875);
PAINT SKYBLUE (-1980 2875);
FORCEPROP 1 LASTPIN (-2025 2950) $PN 1
J 0
(-2020 2912);
DISPLAY 0.617021 (-2020 2912);
PAINT ORANGE (-2020 2912);
FORCEPROP 1 LAST LOCATION R1R5
J 0
(-1980 2975);
DISPLAY 0.617021 (-1980 2975);
PAINT AQUA (-1980 2975);
FORCEPROP 1 LAST VALUE 4.75K
J 0
(-1980 2925);
DISPLAY 0.617021 (-1980 2925);
PAINT SKYBLUE (-1980 2925);
FORCEPROP 1 LAST WATTAGE 1/16W
J 0
(-1985 2825);
DISPLAY 0.617021 (-1985 2825);
PAINT SKYBLUE (-1985 2825);
FORCEPROP 1 LAST PART_NUMBER G21796-072
J 0
(-1985 2725);
DISPLAY 0.617021 (-1985 2725);
PAINT BLUE (-1985 2725);
FORCEPROP 2 LAST CDS_LIB mstr_discrete
J 0
(-2025 2850);
PAINT MONO (-2025 2850);
DISPLAY INVISIBLE (-2025 2850);
FORCEPROP 2 LAST CDS_LOCATION R1R5
J 0
(-1980 2975);
DISPLAY 0.617021 (-1980 2975);
PAINT AQUA (-1980 2975);
DISPLAY INVISIBLE (-1980 2975);
FORCEPROP 2 LAST ROOM FAST_PROCHOT
J 0
(-1975 3025);
DISPLAY 1.021277 (-1975 3025);
PAINT ORANGE (-1975 3025);
DISPLAY INVISIBLE (-1975 3025);
FORCEPROP 1 LAST PATH I73
J 0
(-1975 3025);
DISPLAY 0.978723 (-1975 3025);
PAINT WHITE (-1975 3025);
DISPLAY INVISIBLE (-1975 3025);
FORCEPROP 2 LAST SEC 1
J 0
(-1975 3075);
PAINT MONO (-1975 3075);
DISPLAY INVISIBLE (-1975 3075);
FORCEPROP 2 LAST SEC_TYPE 0402
J 0
(-1975 3075);
DISPLAY 1.021277 (-1975 3075);
PAINT ORANGE (-1975 3075);
DISPLAY INVISIBLE (-1975 3075);
FORCEPROP 2 LAST BOM_COST FAST_PROCHOT
J 0
(-1975 3075);
DISPLAY 1.021277 (-1975 3075);
PAINT ORANGE (-1975 3075);
DISPLAY INVISIBLE (-1975 3075);
FORCEADD RES..1
(-1900 4775);
FORCEPROP 1 LAST WATTAGE 1/16W
J 2
(-1925 4625);
DISPLAY 0.617021 (-1925 4625);
PAINT SKYBLUE (-1925 4625);
FORCEPROP 1 LAST VALUE 33.2
J 2
(-1925 4675);
DISPLAY 0.617021 (-1925 4675);
PAINT SKYBLUE (-1925 4675);
FORCEPROP 1 LAST LOCATION R2P4
J 0
(-1950 4825);
DISPLAY 0.617021 (-1950 4825);
PAINT AQUA (-1950 4825);
FORCEPROP 1 LAST TOLERANCE 1%
J 0
(-1900 4675);
DISPLAY 0.617021 (-1900 4675);
PAINT SKYBLUE (-1900 4675);
FORCEPROP 1 LAST PART_NUMBER G21796-074
J 0
(-1950 4875);
DISPLAY 0.617021 (-1950 4875);
PAINT BLUE (-1950 4875);
FORCEPROP 1 LAST MATERIAL CHIP
J 0
(-1900 4625);
DISPLAY 0.617021 (-1900 4625);
PAINT SKYBLUE (-1900 4625);
FORCEPROP 1 LAST PACK_TYPE 0402
J 0
(-1775 4625);
DISPLAY 0.617021 (-1775 4625);
PAINT SKYBLUE (-1775 4625);
FORCEPROP 1 LASTPIN (-2000 4775) $PN 1
J 0
(-1988 4787);
DISPLAY 0.787234 (-1988 4787);
PAINT ORANGE (-1988 4787);
DISPLAY INVISIBLE (-1988 4787);
FORCEPROP 2 LAST CDS_LOCATION R2P4
J 0
(-1950 4825);
DISPLAY 0.617021 (-1950 4825);
PAINT AQUA (-1950 4825);
DISPLAY INVISIBLE (-1950 4825);
FORCEPROP 1 LASTPIN (-1800 4775) $PN 2
J 0
(-1838 4787);
DISPLAY 0.787234 (-1838 4787);
PAINT ORANGE (-1838 4787);
DISPLAY INVISIBLE (-1838 4787);
FORCEPROP 2 LAST CDS_LIB mstr_discrete
J 0
(-1900 4775);
PAINT ORANGE (-1900 4775);
DISPLAY INVISIBLE (-1900 4775);
FORCEPROP 1 LAST PATH I74
J 0
(-1950 4925);
DISPLAY 0.978723 (-1950 4925);
PAINT WHITE (-1950 4925);
DISPLAY INVISIBLE (-1950 4925);
FORCEPROP 2 LAST $SEC 1
J 0
(-1950 4975);
PAINT MONO (-1950 4975);
DISPLAY INVISIBLE (-1950 4975);
FORCEPROP 2 LAST CDS_SEC 1
J 0
(-1950 4975);
PAINT MONO (-1950 4975);
DISPLAY INVISIBLE (-1950 4975);
FORCEADD CAP_A..1
(-5100 3350);
FORCEPROP 1 LASTPIN (-5100 3250) $PN 2
J 0
(-5090 3230);
DISPLAY 0.617021 (-5090 3230);
PAINT ORANGE (-5090 3230);
FORCEPROP 1 LAST MATERIAL X7R
J 0
(-5050 3250);
DISPLAY 0.617021 (-5050 3250);
PAINT SKYBLUE (-5050 3250);
FORCEPROP 1 LAST TOLERANCE 10%
J 0
(-5050 3300);
DISPLAY 0.617021 (-5050 3300);
PAINT SKYBLUE (-5050 3300);
FORCEPROP 1 LAST PACK_TYPE 0402V
J 0
(-5050 3150);
DISPLAY 0.617021 (-5050 3150);
PAINT SKYBLUE (-5050 3150);
FORCEPROP 1 LASTPIN (-5100 3450) $PN 1
J 0
(-5090 3430);
DISPLAY 0.617021 (-5090 3430);
PAINT ORANGE (-5090 3430);
FORCEPROP 1 LAST VOLTAGE 16V
J 0
(-5050 3350);
DISPLAY 0.617021 (-5050 3350);
PAINT SKYBLUE (-5050 3350);
FORCEPROP 1 LAST VALUE 0.1UF
J 0
(-5050 3400);
DISPLAY 0.617021 (-5050 3400);
PAINT SKYBLUE (-5050 3400);
FORCEPROP 1 LAST LOCATION C2P1
J 0
(-5050 3450);
DISPLAY 0.617021 (-5050 3450);
PAINT AQUA (-5050 3450);
FORCEPROP 1 LAST PART_NUMBER A36096-030
J 0
(-5050 3200);
DISPLAY 0.617021 (-5050 3200);
PAINT BLUE (-5050 3200);
FORCEPROP 2 LAST CDS_LOCATION C2P1
J 0
(-5050 3450);
DISPLAY 0.617021 (-5050 3450);
PAINT AQUA (-5050 3450);
DISPLAY INVISIBLE (-5050 3450);
FORCEPROP 2 LAST CDS_LIB dev_discrete
J 0
(-5100 3350);
PAINT ORANGE (-5100 3350);
DISPLAY INVISIBLE (-5100 3350);
FORCEPROP 2 LAST CDS_SEC 1
J 0
(-5050 3500);
PAINT ORANGE (-5050 3500);
DISPLAY INVISIBLE (-5050 3500);
FORCEPROP 2 LAST SEC 1
J 0
(-5050 3550);
DISPLAY 0.680851 (-5050 3550);
PAINT MONO (-5050 3550);
DISPLAY INVISIBLE (-5050 3550);
FORCEPROP 2 LAST ROOM FAST_PROCHOT
J 0
(-5050 3500);
DISPLAY 1.021277 (-5050 3500);
PAINT ORANGE (-5050 3500);
DISPLAY INVISIBLE (-5050 3500);
FORCEPROP 1 LAST PATH I8
J 0
(-5050 3500);
DISPLAY 0.978723 (-5050 3500);
PAINT WHITE (-5050 3500);
DISPLAY INVISIBLE (-5050 3500);
FORCEPROP 2 LAST SEC_TYPE 0402V
J 0
(-5050 3550);
DISPLAY 1.021277 (-5050 3550);
PAINT ORANGE (-5050 3550);
DISPLAY INVISIBLE (-5050 3550);
FORCEPROP 2 LAST BOM_COST FAST_PROCHOT
J 0
(-5050 3550);
DISPLAY 1.021277 (-5050 3550);
PAINT ORANGE (-5050 3550);
DISPLAY INVISIBLE (-5050 3550);
FORCEADD DNS..2
(-4520 3920);
PAINT RED (-4520 3920);
FORCEPROP 1 LAST COMMENT_BODY TRUE
R 1
J 0
(-4445 3695);
DISPLAY 0.872340 (-4445 3695);
PAINT GREEN (-4445 3695);
DISPLAY INVISIBLE (-4445 3695);
FORCEPROP 2 LAST CDS_LIB mstr_misc
J 0
(-4520 3920);
PAINT ORANGE (-4520 3920);
DISPLAY INVISIBLE (-4520 3920);
FORCEADD CAD_NOTE..1
(-1100 5275);
FORCEPROP 0 LAST L2 TRI STATE BUFFER
J 0
(-1250 5100);
DISPLAY 1.021277 (-1250 5100);
PAINT ORANGE (-1250 5100);
FORCEPROP 0 LAST L1 PLACE CAP CLOSE TO VCC ON
J 0
(-1250 5150);
DISPLAY 1.021277 (-1250 5150);
PAINT ORANGE (-1250 5150);
FORCEPROP 2 LAST CDS_LIB mstr_symbols
J 0
(-1100 5275);
PAINT ORANGE (-1100 5275);
DISPLAY INVISIBLE (-1100 5275);
FORCEPROP 1 LAST COMMENT_BODY TRUE
J 0
(-1075 5375);
DISPLAY 0.978723 (-1075 5375);
PAINT ORANGE (-1075 5375);
DISPLAY INVISIBLE (-1075 5375);
FORCEADD DESIGN_NOTE..1
(-4625 3550);
FORCEPROP 0 LAST L3 COMES FROM A PUSH-PULL TRI-STATE BUFFER
J 0
(-4825 3325);
DISPLAY 0.808511 (-4825 3325);
PAINT ORANGE (-4825 3325);
FORCEPROP 0 LAST L2 AN OPEN DRAIN NET. IRQ_SML1_PMBUS_ALERT_BUF_N
J 0
(-4825 3375);
DISPLAY 0.808511 (-4825 3375);
PAINT ORANGE (-4825 3375);
FORCEPROP 0 LAST L1 74LVC1G07 USED TO MAKE IRQ_SML1_PMBUS_ALERT_BUF_N
J 0
(-4825 3425);
DISPLAY 0.808511 (-4825 3425);
PAINT ORANGE (-4825 3425);
FORCEPROP 2 LAST CDS_LIB mstr_symbols
J 0
(-4625 3550);
PAINT MONO (-4625 3550);
DISPLAY INVISIBLE (-4625 3550);
FORCEPROP 1 LAST COMMENT_BODY TRUE
J 0
(-4600 3650);
DISPLAY 0.978723 (-4600 3650);
PAINT ORANGE (-4600 3650);
DISPLAY INVISIBLE (-4600 3650);
FORCEADD CAD_NOTE..1
(-4675 1500);
FORCEPROP 0 LAST L2 74HC1G126
J 0
(-4825 1325);
DISPLAY 1.021277 (-4825 1325);
PAINT ORANGE (-4825 1325);
FORCEPROP 0 LAST L1 PLACE CAP CLOSE TO VCC ON
J 0
(-4825 1375);
DISPLAY 1.021277 (-4825 1375);
PAINT ORANGE (-4825 1375);
FORCEPROP 2 LAST CDS_LIB mstr_symbols
J 0
(-4675 1500);
PAINT ORANGE (-4675 1500);
DISPLAY INVISIBLE (-4675 1500);
FORCEPROP 1 LAST COMMENT_BODY TRUE
J 0
(-4650 1600);
DISPLAY 0.978723 (-4650 1600);
PAINT ORANGE (-4650 1600);
DISPLAY INVISIBLE (-4650 1600);
FORCEADD CAD_NOTE..1
(50 4950);
FORCEPROP 0 LAST L2 74LVC08
J 0
(-100 4775);
DISPLAY 1.021277 (-100 4775);
PAINT ORANGE (-100 4775);
FORCEPROP 0 LAST L1 PLACE CAP CLOSE TO VCC ON
J 0
(-100 4825);
DISPLAY 1.021277 (-100 4825);
PAINT ORANGE (-100 4825);
FORCEPROP 1 LAST COMMENT_BODY TRUE
J 0
(75 5050);
DISPLAY 0.978723 (75 5050);
PAINT ORANGE (75 5050);
DISPLAY INVISIBLE (75 5050);
FORCEPROP 2 LAST CDS_LIB mstr_symbols
J 0
(50 4950);
PAINT ORANGE (50 4950);
DISPLAY INVISIBLE (50 4950);
FORCEADD DNS..2
(-3695 4245);
PAINT RED (-3695 4245);
FORCEPROP 1 LAST COMMENT_BODY TRUE
R 1
J 0
(-3620 4020);
DISPLAY 0.872340 (-3620 4020);
PAINT GREEN (-3620 4020);
DISPLAY INVISIBLE (-3620 4020);
FORCEPROP 2 LAST CDS_LIB mstr_misc
J 0
(-3695 4245);
PAINT ORANGE (-3695 4245);
DISPLAY INVISIBLE (-3695 4245);
FORCEADD CAD_NOTE..1
(-4675 3250);
FORCEPROP 0 LAST L2 1G07 BUFFER
J 0
(-4825 3075);
DISPLAY 1.021277 (-4825 3075);
PAINT ORANGE (-4825 3075);
FORCEPROP 0 LAST L1 PLACE CAP CLOSE TO VCC ON
J 0
(-4825 3125);
DISPLAY 1.021277 (-4825 3125);
PAINT ORANGE (-4825 3125);
FORCEPROP 2 LAST CDS_LIB mstr_symbols
J 0
(-4675 3250);
PAINT ORANGE (-4675 3250);
DISPLAY INVISIBLE (-4675 3250);
FORCEPROP 1 LAST COMMENT_BODY TRUE
J 0
(-4650 3350);
DISPLAY 0.978723 (-4650 3350);
PAINT ORANGE (-4650 3350);
DISPLAY INVISIBLE (-4650 3350);
FORCEADD CAD_NOTE..1
(-1125 1875);
FORCEPROP 0 LAST L1 PLACE CAP CLOSE TO VCC ON
J 0
(-1275 1750);
DISPLAY 1.021277 (-1275 1750);
PAINT ORANGE (-1275 1750);
FORCEPROP 0 LAST L2 74LVC1G07
J 0
(-1275 1700);
DISPLAY 1.021277 (-1275 1700);
PAINT ORANGE (-1275 1700);
FORCEPROP 1 LAST COMMENT_BODY TRUE
J 0
(-1100 1975);
DISPLAY 0.978723 (-1100 1975);
PAINT ORANGE (-1100 1975);
DISPLAY INVISIBLE (-1100 1975);
FORCEPROP 2 LAST CDS_LIB mstr_symbols
J 0
(-1125 1875);
PAINT ORANGE (-1125 1875);
DISPLAY INVISIBLE (-1125 1875);
FORCEADD INTEL_CORP_BPAGE..1
(2100 700);
FORCEPROP 1 LAST CDS_CON_LAST_MODIFIED Tue Dec 01 11:52:12 2015
J 0
(675 1025);
PAINT ORANGE (675 1025);
DISPLAY INVISIBLE (675 1025);
FORCEPROP 1 LAST CUSTOM_TXT_CDS <CURRENT_DESIGN_SHEET> OF <TOTAL_DESIGN_SHEETS>
J 0
(1600 725);
PAINT GREEN (1600 725);
FORCEPROP 1 LAST CUSTOM_TXT_CDS <CON_LAST_MODIFIED>
J 0
(175 1050);
PAINT GREEN (175 1050);
FORCEPROP 2 LAST CUSTOM_TXT_CDS <XR_PAGE_TITLE>
J 0
(-5790 5950);
DISPLAY 0.638298 (-5790 5950);
PAINT PINK (-5790 5950);
DISPLAY INVISIBLE (-5790 5950);
FORCEPROP 1 LAST SCH_TITLE FAST PROCHOT LOGIC
J 0
(-5850 750);
DISPLAY 1.212766 (-5850 750);
PAINT ORANGE (-5850 750);
FORCEPROP 1 LAST SCH_ADDRESS3 Santa Clara, CA 95052-8119
J 0
(-1875 725);
DISPLAY 0.617021 (-1875 725);
PAINT GREEN (-1875 725);
FORCEPROP 1 LAST SCH_ADDRESS2 P.O. BOX 58119
J 0
(-1875 775);
DISPLAY 0.617021 (-1875 775);
PAINT GREEN (-1875 775);
FORCEPROP 1 LAST SCH_ADDRESS1 2200 Mission College Blvd.
J 0
(-1875 825);
DISPLAY 0.617021 (-1875 825);
PAINT GREEN (-1875 825);
FORCEPROP 1 LAST SCH_NUMBER H4694802
J 0
(800 850);
DISPLAY 1.212766 (800 850);
PAINT YELLOW (800 850);
FORCEPROP 1 LAST SCH_DEPT BESD
J 1
(-2350 800);
DISPLAY 1.212766 (-2350 800);
PAINT YELLOW (-2350 800);
FORCEPROP 1 LAST SCH_REV 2.420
J 0
(1850 850);
DISPLAY 0.978723 (1850 850);
PAINT YELLOW (1850 850);
FORCEPROP 2 LAST PAGE_BORDER TRUE
J 0
(-5790 5950);
DISPLAY 0.851064 (-5790 5950);
PAINT PINK (-5790 5950);
DISPLAY INVISIBLE (-5790 5950);
FORCEPROP 1 LAST COMMENT_BODY TRUE
J 0
(2112 712);
DISPLAY 0.468085 (2112 712);
PAINT GREEN (2112 712);
DISPLAY INVISIBLE (2112 712);
FORCEPROP 2 LAST CDS_LIB mstr_symbols
J 0
(2100 700);
PAINT MONO (2100 700);
DISPLAY INVISIBLE (2100 700);
FORCEPROP 2 LAST CDS_XR_PAGE_TITLE CR-170 : @BASEBOARD_FAB2_LIB.BASEBOARD_FAB2(SCH_1):PAGE170
J 0
(-5790 5950);
DISPLAY 0.638298 (-5790 5950);
PAINT PINK (-5790 5950);
DISPLAY INVISIBLE (-5790 5950);
WIRE 16 -1 (-2350 5425)(-2350 5350);
WIRE 16 -1 (-5150 1100)(-5150 1225);
WIRE 16 -1 (-5150 1425)(-5150 1525);
WIRE 16 -1 (-425 4550)(-425 4675);
WIRE 16 -1 (-425 4875)(-425 4975);
WIRE 16 -1 (-1575 5200)(-1575 5300);
WIRE 16 -1 (-1575 4875)(-1575 5000);
WIRE 16 -1 (-3700 4000)(-3700 4150);
WIRE 16 -1 (-1600 1800)(-1600 1900);
WIRE 16 -1 (-1600 1475)(-1600 1600);
WIRE 16 -1 (-4150 5275)(-3825 5275);
WIRE 16 -1 (-4150 5275)(-4150 5200);
WIRE 16 -1 (-3825 5425)(-3825 5275);
WIRE 16 -1 (-3825 5275)(-3825 5200);
WIRE 16 -1 (-3450 2300)(-3450 2175);
WIRE 16 -1 (-5100 3450)(-5100 3550);
WIRE 16 -1 (-4150 3950)(-4150 4025);
WIRE 16 -1 (-4600 4450)(-4600 4525);
WIRE 16 -1 (-4525 3750)(-4525 3825);
WIRE 16 -1 (-2950 2950)(-2950 2875);
WIRE 16 -1 (-2950 1625)(-2950 1700);
WIRE 16 -1 (-5100 3125)(-5100 3250);
WIRE 16 -1 (-3150 5425)(-3150 5200);
WIRE 16 -1 (-2025 3025)(-2025 2950);
WIRE 16 -1 (-100 4075)(750 4075);
FORCEPROP 2 LAST SIG_NAME FM_FAST_PROCHOT_THROTTLE_IN_N
J 0
(-35 4085);
DISPLAY 0.617021 (-35 4085);
PAINT ORANGE (-35 4085);
WIRE 16 -1 (-775 4125)(-400 4125);
WIRE 16 -1 (-775 4375)(-775 4125);
WIRE 16 -1 (-1250 4375)(-775 4375);
FORCEPROP 2 LAST SIG_NAME FM_FAST_PROCHOT_AND_OUT_0_N
J 0
(-1185 4385);
DISPLAY 0.617021 (-1185 4385);
PAINT ORANGE (-1185 4385);
FORCEPROP 2 LASTPROP $XRERR UNIQUE?
J 0
(-1425 4385);
DISPLAY 0.638298 (-1425 4385);
PAINT MONO (-1425 4385);
DISPLAY INVISIBLE (-1425 4385);
WIRE 16 -1 (-1800 4775)(-1650 4775);
WIRE 16 -1 (-1650 4775)(-1650 4425);
WIRE 16 -1 (-1650 4425)(-1550 4425);
WIRE 16 -1 (-1650 4425)(-2475 4425);
FORCEPROP 2 LAST SIG_NAME IRQ_FORCE_NM_THROTTLE_N
J 0
(-2435 4435);
DISPLAY 0.617021 (-2435 4435);
PAINT ORANGE (-2435 4435);
WIRE 16 -1 (-2475 4325)(-1550 4325);
FORCEPROP 2 LAST SIG_NAME FM_OC_DETECT_N
J 0
(-2435 4335);
DISPLAY 0.617021 (-2435 4335);
PAINT ORANGE (-2435 4335);
WIRE 16 -1 (-2350 5150)(-2350 4775);
FORCEPROP 2 LAST SIG_NAME IRQ_FORCE_NM_THROTTLE_R_N
J 0
(-2335 5010);
DISPLAY 0.617021 (-2335 5010);
PAINT ORANGE (-2335 5010);
FORCEPROP 2 LASTPROP $XRERR UNIQUE?
J 0
(-2575 5010);
DISPLAY 0.638298 (-2575 5010);
PAINT MONO (-2575 5010);
DISPLAY INVISIBLE (-2575 5010);
WIRE 16 -1 (-2350 4775)(-2000 4775);
WIRE 16 -1 (-2475 4775)(-2350 4775);
WIRE 16 -1 (-3150 5000)(-3150 4775);
WIRE 16 -1 (-3150 4775)(-2725 4775);
WIRE 16 -1 (-3350 4775)(-3150 4775);
FORCEPROP 2 LAST SIG_NAME IRQ_SML1_PMBUS_ALERT_BUF_N
J 0
(-3310 4785);
DISPLAY 0.617021 (-3310 4785);
PAINT ORANGE (-3310 4785);
FORCEPROP 2 LASTPROP $XRERR UNIQUE?
J 0
(-3550 4785);
DISPLAY 0.638298 (-3550 4785);
PAINT MONO (-3550 4785);
DISPLAY INVISIBLE (-3550 4785);
WIRE 16 -1 (-3500 4600)(-3500 4675);
WIRE 16 -1 (-4150 4600)(-3500 4600);
FORCEPROP 2 LAST SIG_NAME FM_PMBUS_ALERT_BUF_EN
J 0
(-4135 4610);
DISPLAY 0.617021 (-4135 4610);
PAINT ORANGE (-4135 4610);
FORCEPROP 2 LASTPROP $XRERR UNIQUE?
J 0
(-4375 4610);
DISPLAY 0.638298 (-4375 4610);
PAINT MONO (-4375 4610);
DISPLAY INVISIBLE (-4375 4610);
WIRE 16 -1 (-4150 4600)(-4150 5000);
WIRE 16 -1 (-4150 4425)(-4150 4600);
WIRE 16 -1 (-3825 5000)(-3825 4775);
WIRE 16 -1 (-3700 4775)(-3825 4775);
WIRE 16 -1 (-4950 4775)(-3825 4775);
FORCEPROP 2 LAST SIG_NAME IRQ_SML1_PMBUS_ALERT_N
J 0
(-4950 4785);
DISPLAY 0.617021 (-4950 4785);
PAINT ORANGE (-4950 4785);
WIRE 16 -1 (-3700 4775)(-3650 4775);
WIRE 16 -1 (-3700 4350)(-3700 4775);
WIRE 16 -1 (-750 4025)(-400 4025);
WIRE 16 -1 (-750 3650)(-750 4025);
WIRE 16 -1 (-1250 3650)(-750 3650);
FORCEPROP 2 LAST SIG_NAME FM_FAST_PROCHOT_AND_OUT_1_N
J 0
(-1185 3660);
DISPLAY 0.617021 (-1185 3660);
PAINT ORANGE (-1185 3660);
FORCEPROP 2 LASTPROP $XRERR UNIQUE?
J 0
(-1425 3660);
DISPLAY 0.638298 (-1425 3660);
PAINT MONO (-1425 3660);
DISPLAY INVISIBLE (-1425 3660);
WIRE 16 -1 (-550 2525)(-100 2525);
FORCEPROP 2 LAST SIG_NAME FM_THROTTLE_N
J 0
(-535 2535);
DISPLAY 0.617021 (-535 2535);
PAINT ORANGE (-535 2535);
WIRE 16 -1 (-750 2525)(-1250 2525);
FORCEPROP 0 LAST SIG_NAME FM_THROTTLE_R1_N
J 0
(-1185 2535);
DISPLAY 0.617021 (-1185 2535);
PAINT ORANGE (-1185 2535);
FORCEPROP 2 LASTPROP $XRERR UNIQUE?
J 0
(-1425 2535);
DISPLAY 0.638298 (-1425 2535);
PAINT MONO (-1425 2535);
DISPLAY INVISIBLE (-1425 2535);
WIRE 16 -1 (-1500 2525)(-2025 2525);
WIRE 16 -1 (-2025 2750)(-2025 2525);
WIRE 16 -1 (-2025 2525)(-2375 2525);
FORCEPROP 2 LAST SIG_NAME FM_FAST_PROCHOT_THROTTLE_DLY_BUF_N
J 0
(-2360 2535);
DISPLAY 0.617021 (-2360 2535);
PAINT ORANGE (-2360 2535);
FORCEPROP 2 LASTPROP $XRERR UNIQUE?
J 0
(-2600 2535);
DISPLAY 0.638298 (-2600 2535);
PAINT MONO (-2600 2535);
DISPLAY INVISIBLE (-2600 2535);
WIRE 16 -1 (-2425 3600)(-1550 3600);
FORCEPROP 2 LAST SIG_NAME FM_HSC_TIMER_EXP_N
J 0
(-2360 3610);
DISPLAY 0.617021 (-2360 3610);
PAINT ORANGE (-2360 3610);
WIRE 16 -1 (-2425 3700)(-1550 3700);
FORCEPROP 2 LAST SIG_NAME IRQ_UV_DETECT_N
J 0
(-2360 3710);
DISPLAY 0.617021 (-2360 3710);
PAINT ORANGE (-2360 3710);
WIRE 16 -1 (-2525 2250)(-2525 2425);
WIRE 16 -1 (-2950 2250)(-2525 2250);
FORCEPROP 2 LAST SIG_NAME FM_FAST_PROCHOT_EN
J 0
(-2935 2260);
DISPLAY 0.617021 (-2935 2260);
PAINT ORANGE (-2935 2260);
FORCEPROP 2 LASTPROP $XRERR UNIQUE?
J 0
(-3175 2260);
DISPLAY 0.638298 (-3175 2260);
PAINT MONO (-3175 2260);
DISPLAY INVISIBLE (-3175 2260);
WIRE 16 -1 (-2950 2250)(-2950 2675);
WIRE 16 -1 (-2950 2100)(-2950 2250);
WIRE 16 -1 (-3700 2525)(-2675 2525);
FORCEPROP 2 LAST SIG_NAME FM_FAST_PROCHOT_THROTTLE_DLY_N
J 0
(-3660 2535);
DISPLAY 0.617021 (-3660 2535);
PAINT ORANGE (-3660 2535);
WIRE 16 -1 (-3450 1975)(-3450 1800);
WIRE 16 -1 (-3450 1800)(-3150 1800);
WIRE 16 -1 (-3950 1800)(-3450 1800);
FORCEPROP 2 LAST SIG_NAME FM_FAST_PROCHOT_EN_N
J 0
(-3910 1810);
DISPLAY 0.617021 (-3910 1810);
PAINT ORANGE (-3910 1810);
WIRE 16 -1 (-4525 4125)(-4350 4125);
WIRE 16 -1 (-4600 4125)(-4525 4125);
WIRE 16 -1 (-4525 4025)(-4525 4125);
WIRE 16 -1 (-4600 4250)(-4600 4125);
WIRE 16 -1 (-4950 4125)(-4600 4125);
FORCEPROP 2 LAST SIG_NAME FM_PMBUS_ALERT_BUF_EN_N
J 0
(-4960 4135);
DISPLAY 0.617021 (-4960 4135);
PAINT ORANGE (-4960 4135);
DOT 1 (-4600 4125);
DOT 1 (-4525 4125);
DOT 1 (-4150 4600);
DOT 1 (-3450 1800);
DOT 1 (-2950 2250);
DOT 1 (-2025 2525);
DOT 1 (-3825 4775);
DOT 1 (-3700 4775);
DOT 1 (-3150 4775);
DOT 1 (-3825 5275);
DOT 1 (-2350 4775);
DOT 1 (-1650 4425);
FORCENOTE
FROM BMC AND IE
(-4425 2200) 0;
DISPLAY LEFT (-4425 2200);
DISPLAY 1.021277 (-4425 2200);
PAINT PURPLE (-4425 2200);
FORCENOTE
FROM CPLD
(-4200 2575) 0;
DISPLAY LEFT (-4200 2575);
DISPLAY 1.021277 (-4200 2575);
PAINT PURPLE (-4200 2575);
FORCENOTE
FROM HSC TIMER
(-3125 3475) 0;
DISPLAY LEFT (-3125 3475);
DISPLAY 1.021277 (-3125 3475);
PAINT PURPLE (-3125 3475);
FORCENOTE
FROM UNDER VOLTAGE MONITOR
(-3150 3775) 0;
DISPLAY LEFT (-3150 3775);
DISPLAY 1.021277 (-3150 3775);
PAINT PURPLE (-3150 3775);
FORCENOTE
FROM OVER CURRENT MONITOR
(-3150 4200) 0;
DISPLAY LEFT (-3150 4200);
DISPLAY 1.021277 (-3150 4200);
PAINT PURPLE (-3150 4200);
FORCENOTE
TO CPLD
(1150 4050) 0;
DISPLAY LEFT (1150 4050);
DISPLAY 1.021277 (1150 4050);
PAINT PURPLE (1150 4050);
QUIT
